G04*
G04 #@! TF.GenerationSoftware,Altium Limited,Altium Designer,23.7.1 (13)*
G04*
G04 Layer_Color=128*
%FSLAX25Y25*%
%MOIN*%
G70*
G04*
G04 #@! TF.SameCoordinates,AF00DCEB-AC48-4C7C-91EA-99F42E284231*
G04*
G04*
G04 #@! TF.FilePolarity,Positive*
G04*
G01*
G75*
%ADD293C,0.00200*%
D293*
X296024Y-115512D02*
X300039D01*
X298031Y-117520D02*
Y-113504D01*
X296024Y-145512D02*
X300039D01*
X298031Y-147520D02*
Y-143504D01*
X296024Y-155512D02*
X300039D01*
X298031Y-157520D02*
Y-153504D01*
X296024Y-125512D02*
X300039D01*
X298031Y-127520D02*
Y-123504D01*
X296024Y-135512D02*
X300039D01*
X298031Y-137520D02*
Y-133504D01*
X319094Y-145669D02*
X323425D01*
X321260Y-147835D02*
Y-143504D01*
X319094Y-155669D02*
X323425D01*
X321260Y-157835D02*
Y-153504D01*
X319094Y-135669D02*
X323425D01*
X321260Y-137835D02*
Y-133504D01*
X319094Y-125669D02*
X323425D01*
X321260Y-127835D02*
Y-123504D01*
X597210Y-805D02*
X609010D01*
X603110Y-6705D02*
Y5095D01*
X570866Y7445D02*
X577953D01*
X574409Y3902D02*
Y10988D01*
X570866Y-9055D02*
X577953D01*
X574409Y-12598D02*
Y-5512D01*
X549166Y7445D02*
X556253D01*
X552709Y3902D02*
Y10988D01*
X549166Y-9055D02*
X556253D01*
X552709Y-12598D02*
Y-5512D01*
X-6260Y0D02*
X6260D01*
X0Y-6260D02*
Y6260D01*
X606988Y-288779D02*
X609547D01*
X608268Y-290059D02*
Y-287500D01*
X606988Y-271260D02*
X609547D01*
X608268Y-272539D02*
Y-269980D01*
X618898Y-263583D02*
X621260D01*
X620079Y-264764D02*
Y-262402D01*
X618898Y-296457D02*
X621260D01*
X620079Y-297638D02*
Y-295276D01*
X136801Y-22096D02*
X139793D01*
X138297Y-23592D02*
Y-20600D01*
X136801Y-69340D02*
X139793D01*
X138297Y-70836D02*
Y-67844D01*
X191732Y394D02*
X198031D01*
X194882Y-2756D02*
Y3543D01*
X192717Y-78347D02*
X197047D01*
X194882Y-80512D02*
Y-76181D01*
X493307Y-271358D02*
X499606D01*
X496457Y-274508D02*
Y-268209D01*
X573032Y-271358D02*
X577362D01*
X575197Y-273524D02*
Y-269193D01*
X345768Y-38976D02*
X362303D01*
X354035Y-47244D02*
Y-30709D01*
X416535Y-38976D02*
X433071D01*
X424803Y-47244D02*
Y-30709D01*
X136801Y-69340D02*
X139793D01*
X138297Y-70836D02*
Y-67844D01*
X136801Y-53592D02*
X139793D01*
X138297Y-55088D02*
Y-52096D01*
X527559Y-112205D02*
X544095D01*
X535827Y-120472D02*
Y-103937D01*
X389379Y-181769D02*
X391545D01*
X390462Y-182852D02*
Y-180686D01*
X310639Y-181769D02*
X312805D01*
X311722Y-182852D02*
Y-180686D01*
X539597Y-320167D02*
X542589D01*
X541093Y-321663D02*
Y-318671D01*
X555345Y-320167D02*
X558337D01*
X556841Y-321663D02*
Y-318671D01*
X508101Y-320167D02*
X511093D01*
X509597Y-321663D02*
Y-318671D01*
X555345Y-320167D02*
X558337D01*
X556841Y-321663D02*
Y-318671D01*
X182271Y-334252D02*
X190171D01*
X186221Y-338202D02*
Y-330302D01*
X194081Y-334252D02*
X201981D01*
X198031Y-338202D02*
Y-330302D01*
X54318Y-163779D02*
X62218D01*
X58268Y-167729D02*
Y-159829D01*
X205892Y-334252D02*
X213792D01*
X209842Y-338202D02*
Y-330302D01*
X54318Y-323622D02*
X62218D01*
X58268Y-327572D02*
Y-319672D01*
X214160Y-163779D02*
X222060D01*
X218110Y-167729D02*
Y-159829D01*
X54318Y-243701D02*
X62218D01*
X58268Y-247651D02*
Y-239751D01*
X170271Y-334252D02*
X178171D01*
X174221Y-338202D02*
Y-330302D01*
X214160Y-323622D02*
X222060D01*
X218110Y-327572D02*
Y-319672D01*
X158271Y-334252D02*
X166171D01*
X162221Y-338202D02*
Y-330302D01*
X389369Y-329890D02*
X391535D01*
X390452Y-330973D02*
Y-328807D01*
X310629Y-329890D02*
X312795D01*
X311712Y-330973D02*
Y-328807D01*
X259999Y-294702D02*
X262165D01*
X261082Y-295785D02*
Y-293619D01*
X259999Y-215962D02*
X262165D01*
X261082Y-217045D02*
Y-214879D01*
X447490Y-215972D02*
X449656D01*
X448573Y-217055D02*
Y-214889D01*
X447490Y-294712D02*
X449656D01*
X448573Y-295795D02*
Y-293629D01*
X195876Y-315719D02*
X205876D01*
X200876Y-320719D02*
Y-310719D01*
X70768Y-321622D02*
X80768D01*
X75768Y-326622D02*
Y-316622D01*
X73268Y-159780D02*
X83268D01*
X78268Y-164779D02*
Y-154780D01*
X170271Y-334252D02*
X178171D01*
X174221Y-338202D02*
Y-330302D01*
X194081Y-334252D02*
X201981D01*
X198031Y-338202D02*
Y-330302D01*
X205892Y-334252D02*
X213792D01*
X209842Y-338202D02*
Y-330302D01*
X214160Y-163779D02*
X222060D01*
X218110Y-167729D02*
Y-159829D01*
X214160Y-323622D02*
X222060D01*
X218110Y-327572D02*
Y-319672D01*
X54318Y-323622D02*
X62218D01*
X58268Y-327572D02*
Y-319672D01*
X54318Y-243701D02*
X62218D01*
X58268Y-247651D02*
Y-239751D01*
X54318Y-163779D02*
X62218D01*
X58268Y-167729D02*
Y-159829D01*
X182271Y-334252D02*
X190171D01*
X186221Y-338202D02*
Y-330302D01*
X158271Y-334252D02*
X166171D01*
X162221Y-338202D02*
Y-330302D01*
X195610Y-171879D02*
X205610D01*
X200610Y-176880D02*
Y-166879D01*
X447287Y-334056D02*
X459098D01*
X453193Y-339962D02*
Y-328151D01*
X250687Y-177056D02*
X262498D01*
X256593Y-182962D02*
Y-171151D01*
X250787Y-334056D02*
X262598D01*
X256693Y-339962D02*
Y-328151D01*
X447287Y-177056D02*
X459098D01*
X453193Y-182962D02*
Y-171151D01*
X-21811Y-326781D02*
X-15118D01*
X-18464Y-330128D02*
Y-323435D01*
X-11417Y-316781D02*
X-5512D01*
X-8465Y-319734D02*
Y-313828D01*
X-1811Y-326781D02*
X4882D01*
X1535Y-330128D02*
Y-323435D01*
X-1811Y-306781D02*
X4882D01*
X1535Y-310128D02*
Y-303435D01*
X-21811Y-306781D02*
X-15118D01*
X-18464Y-310128D02*
Y-303435D01*
X-21811Y-273630D02*
X-15118D01*
X-18465Y-276976D02*
Y-270284D01*
X-11417Y-263630D02*
X-5512D01*
X-8465Y-266583D02*
Y-260677D01*
X-1811Y-273630D02*
X4882D01*
X1535Y-276976D02*
Y-270284D01*
X-1811Y-253630D02*
X4882D01*
X1535Y-256976D02*
Y-250284D01*
X-21811Y-253630D02*
X-15118D01*
X-18465Y-256976D02*
Y-250284D01*
X-21811Y-220480D02*
X-15118D01*
X-18465Y-223827D02*
Y-217134D01*
X-11417Y-210480D02*
X-5512D01*
X-8465Y-213433D02*
Y-207528D01*
X-1811Y-220480D02*
X4882D01*
X1535Y-223827D02*
Y-217134D01*
X-1811Y-200480D02*
X4882D01*
X1535Y-203827D02*
Y-197134D01*
X-21811Y-200480D02*
X-15118D01*
X-18465Y-203827D02*
Y-197134D01*
X-21811Y-167332D02*
X-15118D01*
X-18464Y-170679D02*
Y-163986D01*
X-11417Y-157332D02*
X-5512D01*
X-8465Y-160285D02*
Y-154379D01*
X-1811Y-167332D02*
X4882D01*
X1535Y-170679D02*
Y-163986D01*
X-1811Y-147332D02*
X4882D01*
X1535Y-150679D02*
Y-143986D01*
X-21811Y-147332D02*
X-15118D01*
X-18464Y-150679D02*
Y-143986D01*
X607677Y-98189D02*
X611221D01*
X609449Y-99961D02*
Y-96417D01*
X607677Y-108189D02*
X611221D01*
X609449Y-109961D02*
Y-106417D01*
X607677Y-118189D02*
X611221D01*
X609449Y-119961D02*
Y-116417D01*
X607677Y-128189D02*
X611221D01*
X609449Y-129961D02*
Y-126417D01*
X607677Y-138189D02*
X611221D01*
X609449Y-139961D02*
Y-136417D01*
X607677Y-148189D02*
X611221D01*
X609449Y-149961D02*
Y-146417D01*
X617677Y-98189D02*
X621220D01*
X619449Y-99961D02*
Y-96417D01*
X617677Y-108189D02*
X621220D01*
X619449Y-109961D02*
Y-106417D01*
X617677Y-118189D02*
X621220D01*
X619449Y-119961D02*
Y-116417D01*
X617677Y-128189D02*
X621220D01*
X619449Y-129961D02*
Y-126417D01*
X617677Y-138189D02*
X621220D01*
X619449Y-139961D02*
Y-136417D01*
X617677Y-148189D02*
X621220D01*
X619449Y-149961D02*
Y-146417D01*
X-6260Y-378395D02*
X6260D01*
X0Y-384655D02*
Y-372135D01*
X181134Y-387757D02*
X181934D01*
X181534Y-388157D02*
Y-387357D01*
X521647Y-270866D02*
X522447D01*
X522047Y-271266D02*
Y-270466D01*
X496220Y-310492D02*
X497020D01*
X496620Y-310892D02*
Y-310092D01*
X61411Y787D02*
X62211D01*
X61811Y387D02*
Y1187D01*
X592907Y-292126D02*
X593707D01*
X593307Y-292526D02*
Y-291726D01*
X244925Y-120837D02*
X245725D01*
X245325Y-121237D02*
Y-120437D01*
X499649Y-256633D02*
X500449D01*
X500049Y-257033D02*
Y-256234D01*
X584639Y-266142D02*
X585439D01*
X585039Y-266542D02*
Y-265742D01*
X560230Y-269291D02*
X561030D01*
X560630Y-269691D02*
Y-268891D01*
X598644Y-275032D02*
X599444D01*
X599044Y-275432D02*
Y-274632D01*
X584639Y-272835D02*
X585439D01*
X585039Y-273235D02*
Y-272435D01*
X581096Y-272835D02*
X581896D01*
X581496Y-273235D02*
Y-272435D01*
X548025Y-269632D02*
X548825D01*
X548425Y-270032D02*
Y-269232D01*
X540693Y-284626D02*
X541493D01*
X541093Y-285026D02*
Y-284226D01*
X541011Y-269932D02*
X541812D01*
X541411Y-270332D02*
Y-269532D01*
X536089Y-269182D02*
X536889D01*
X536489Y-269582D02*
Y-268782D01*
X554324Y-272441D02*
X555124D01*
X554724Y-272841D02*
Y-272041D01*
X555060Y-284401D02*
X555860D01*
X555460Y-284801D02*
Y-284001D01*
X574006Y-280807D02*
X574806D01*
X574406Y-281207D02*
Y-280407D01*
X567125Y-286203D02*
X567925D01*
X567525Y-286603D02*
Y-285803D01*
X581490Y-290158D02*
X582290D01*
X581890Y-290558D02*
Y-289757D01*
X583415Y-275386D02*
X584215D01*
X583815Y-275786D02*
Y-274986D01*
X614423Y-250158D02*
X615223D01*
X614822Y-250558D02*
Y-249758D01*
X604324Y-274803D02*
X605124D01*
X604724Y-275203D02*
Y-274403D01*
X320860Y-166142D02*
X321660D01*
X321260Y-166542D02*
Y-165742D01*
X323222Y-166535D02*
X324022D01*
X323622Y-166935D02*
Y-166135D01*
X149994Y-140157D02*
X150794D01*
X150394Y-140558D02*
Y-139758D01*
X316923Y-114961D02*
X317723D01*
X317323Y-115361D02*
Y-114561D01*
X320860Y-114961D02*
X321660D01*
X321260Y-115361D02*
Y-114561D01*
X320361Y-183851D02*
X321161D01*
X320761Y-184251D02*
Y-183451D01*
X309049Y-211811D02*
X309849D01*
X309449Y-212211D02*
Y-211411D01*
X312986Y-212598D02*
X313786D01*
X313386Y-212998D02*
Y-212198D01*
X123616Y-110236D02*
X124416D01*
X124016Y-110636D02*
Y-109836D01*
X221951Y-98694D02*
X222751D01*
X222351Y-99094D02*
Y-98294D01*
X244876Y-115748D02*
X245676D01*
X245276Y-116148D02*
Y-115348D01*
X211248Y-103695D02*
X212048D01*
X211648Y-104095D02*
Y-103295D01*
X43600Y-137747D02*
X44401D01*
X44001Y-138147D02*
Y-137347D01*
X100329Y-127872D02*
X101129D01*
X100729Y-128271D02*
Y-127471D01*
X-24022Y-181102D02*
X-23222D01*
X-23622Y-181502D02*
Y-180702D01*
X98361Y-129872D02*
X99161D01*
X98761Y-130272D02*
Y-129472D01*
X57022Y-128927D02*
X57822D01*
X57422Y-129327D02*
Y-128527D01*
X88912Y-128140D02*
X89712D01*
X89312Y-128540D02*
Y-127740D01*
X84581Y-128140D02*
X85381D01*
X84981Y-128540D02*
Y-127740D01*
X80251Y-128140D02*
X81051D01*
X80651Y-128540D02*
Y-127740D01*
X88912Y-123809D02*
X89712D01*
X89312Y-124209D02*
Y-123409D01*
X84581Y-123809D02*
X85381D01*
X84981Y-124209D02*
Y-123409D01*
X80251Y-123809D02*
X81051D01*
X80651Y-124209D02*
Y-123409D01*
X88912Y-119478D02*
X89712D01*
X89312Y-119878D02*
Y-119078D01*
X84581Y-119478D02*
X85381D01*
X84981Y-119878D02*
Y-119078D01*
X80251Y-119478D02*
X81051D01*
X80651Y-119878D02*
Y-119078D01*
X98361Y-125872D02*
X99161D01*
X98761Y-126271D02*
Y-125471D01*
X58007Y-137589D02*
X58807D01*
X58407Y-137989D02*
Y-137189D01*
X84644Y-139557D02*
X85444D01*
X85044Y-139957D02*
Y-139157D01*
X80644Y-139557D02*
X81444D01*
X81044Y-139957D02*
Y-139157D01*
X88644Y-139557D02*
X89444D01*
X89044Y-139957D02*
Y-139157D01*
X70802Y-138095D02*
X71602D01*
X71202Y-138495D02*
Y-137695D01*
X78644Y-137936D02*
X79444D01*
X79044Y-138336D02*
Y-137536D01*
X82644Y-137936D02*
X83444D01*
X83044Y-138336D02*
Y-137536D01*
X90644Y-137936D02*
X91444D01*
X91044Y-138336D02*
Y-137536D01*
X86644Y-137936D02*
X87444D01*
X87044Y-138336D02*
Y-137536D01*
X68489Y-137453D02*
X69289D01*
X68889Y-137854D02*
Y-137054D01*
X98361Y-117746D02*
X99161D01*
X98761Y-118146D02*
Y-117346D01*
X98361Y-121871D02*
X99161D01*
X98761Y-122272D02*
Y-121472D01*
X52101Y-119872D02*
X52901D01*
X52501Y-120272D02*
Y-119472D01*
X43734Y-115080D02*
X44534D01*
X44134Y-115480D02*
Y-114680D01*
X44221Y-110628D02*
X45021D01*
X44621Y-111028D02*
Y-110228D01*
X57810Y-108061D02*
X58610D01*
X58210Y-108461D02*
Y-107661D01*
X90644Y-110061D02*
X91444D01*
X91044Y-110461D02*
Y-109661D01*
X78518Y-110029D02*
X79318D01*
X78918Y-110430D02*
Y-109629D01*
X82518Y-110029D02*
X83318D01*
X82918Y-110430D02*
Y-109629D01*
X86581Y-110029D02*
X87381D01*
X86981Y-110430D02*
Y-109629D01*
X80581Y-108061D02*
X81381D01*
X80981Y-108461D02*
Y-107661D01*
X88581Y-108061D02*
X89381D01*
X88981Y-108461D02*
Y-107661D01*
X84581Y-108061D02*
X85381D01*
X84981Y-108461D02*
Y-107661D01*
X138870Y-118898D02*
X139870D01*
X139370Y-119398D02*
Y-118398D01*
X262324Y-107813D02*
X263124D01*
X262724Y-108213D02*
Y-107413D01*
X252682Y-110236D02*
X253482D01*
X253082Y-110636D02*
Y-109836D01*
X317428Y-161260D02*
X318228D01*
X317828Y-161660D02*
Y-160860D01*
X313478Y-161597D02*
X314278D01*
X313878Y-161997D02*
Y-161197D01*
X285720Y-124803D02*
X286720D01*
X286221Y-125303D02*
Y-124303D01*
X285327Y-137795D02*
X286327D01*
X285827Y-138295D02*
Y-137295D01*
X284884Y-154492D02*
X285884D01*
X285384Y-154992D02*
Y-153992D01*
X284146Y-128347D02*
X285146D01*
X284646Y-128847D02*
Y-127847D01*
X283752Y-144095D02*
X284752D01*
X284252Y-144595D02*
Y-143595D01*
X281558Y-151217D02*
X282558D01*
X282058Y-151717D02*
Y-150717D01*
X281390Y-155905D02*
X282390D01*
X281890Y-156405D02*
Y-155405D01*
X280996Y-124409D02*
X281996D01*
X281496Y-124909D02*
Y-123909D01*
X280209Y-137795D02*
X281209D01*
X280709Y-138295D02*
Y-137295D01*
X276150Y-128810D02*
X277150D01*
X276650Y-129310D02*
Y-128310D01*
X275583Y-152559D02*
X276583D01*
X276083Y-153059D02*
Y-152059D01*
X275583Y-141142D02*
X276583D01*
X276083Y-141642D02*
Y-140642D01*
X255405Y-126378D02*
X256405D01*
X255906Y-126878D02*
Y-125878D01*
X255405Y-131496D02*
X256405D01*
X255906Y-131996D02*
Y-130996D01*
X255405Y-137008D02*
X256405D01*
X255906Y-137508D02*
Y-136508D01*
X255405Y-142126D02*
X256405D01*
X255906Y-142626D02*
Y-141626D01*
X256980Y-150394D02*
X257980D01*
X257480Y-150894D02*
Y-149894D01*
X255012Y-146850D02*
X256012D01*
X255512Y-147350D02*
Y-146350D01*
X140051Y-116535D02*
X141051D01*
X140551Y-117035D02*
Y-116035D01*
X367710Y-330315D02*
X368510D01*
X368110Y-330715D02*
Y-329915D01*
X261606Y-387255D02*
X262406D01*
X262006Y-387655D02*
Y-386855D01*
X364954Y-330315D02*
X365754D01*
X365354Y-330715D02*
Y-329915D01*
X264757Y-387253D02*
X265558D01*
X265158Y-387653D02*
Y-386854D01*
X373714Y-346144D02*
X374515D01*
X374114Y-346544D02*
Y-345744D01*
X245939Y-386975D02*
X246739D01*
X246339Y-387375D02*
Y-386575D01*
X249009Y-387253D02*
X249810D01*
X249410Y-387653D02*
Y-386854D01*
X370959Y-346144D02*
X371759D01*
X371359Y-346544D02*
Y-345744D01*
X237592Y-374655D02*
X238392D01*
X237992Y-375055D02*
Y-374255D01*
X367022Y-346144D02*
X367822D01*
X367422Y-346544D02*
Y-345744D01*
X241529Y-374655D02*
X242329D01*
X241929Y-375055D02*
Y-374255D01*
X364266Y-346144D02*
X365066D01*
X364666Y-346544D02*
Y-345744D01*
X353636Y-346144D02*
X354436D01*
X354036Y-346544D02*
Y-345744D01*
X206096Y-374655D02*
X206896D01*
X206496Y-375055D02*
Y-374255D01*
X350880Y-346144D02*
X351680D01*
X351280Y-346544D02*
Y-345744D01*
X210033Y-374655D02*
X210833D01*
X210433Y-375055D02*
Y-374255D01*
X360329Y-346144D02*
X361129D01*
X360729Y-346544D02*
Y-345744D01*
X228931Y-387253D02*
X229731D01*
X229331Y-387653D02*
Y-386854D01*
X357573Y-346144D02*
X358373D01*
X357973Y-346544D02*
Y-345744D01*
X232080Y-387253D02*
X232880D01*
X232480Y-387653D02*
Y-386854D01*
X212395Y-387253D02*
X213195D01*
X212795Y-387653D02*
Y-386854D01*
X215545Y-387253D02*
X216345D01*
X215945Y-387653D02*
Y-386854D01*
X355899Y-330315D02*
X356699D01*
X356299Y-330715D02*
Y-329915D01*
X353143Y-330315D02*
X353943D01*
X353543Y-330715D02*
Y-329915D01*
X218045Y-374108D02*
X218845D01*
X218445Y-374507D02*
Y-373708D01*
X222238Y-374655D02*
X223038D01*
X222638Y-375055D02*
Y-374255D01*
X364067Y-326378D02*
X365067D01*
X364567Y-326878D02*
Y-325878D01*
X357075Y-327776D02*
X358075D01*
X357575Y-328276D02*
Y-327276D01*
X356980Y-332677D02*
X357980D01*
X357480Y-333177D02*
Y-332177D01*
X350287Y-329921D02*
X351287D01*
X350787Y-330421D02*
Y-329421D01*
X359252Y-326841D02*
X360052D01*
X359652Y-327241D02*
Y-326441D01*
X362008Y-326841D02*
X362808D01*
X362408Y-327241D02*
Y-326441D01*
X205405Y-372441D02*
X206405D01*
X205906Y-372941D02*
Y-371941D01*
X210524Y-372441D02*
X211524D01*
X211024Y-372941D02*
Y-371941D01*
X222335Y-372047D02*
X223335D01*
X222835Y-372547D02*
Y-371547D01*
X216823Y-371654D02*
X217823D01*
X217323Y-372153D02*
Y-371153D01*
X237295Y-371654D02*
X238295D01*
X237795Y-372153D02*
Y-371153D01*
X242397Y-371864D02*
X243397D01*
X242897Y-372364D02*
Y-371364D01*
X249894Y-375984D02*
X250894D01*
X250394Y-376484D02*
Y-375484D01*
X258949Y-373228D02*
X259949D01*
X259449Y-373728D02*
Y-372728D01*
X268004Y-372047D02*
X269004D01*
X268504Y-372547D02*
Y-371547D01*
X274303Y-372441D02*
X275303D01*
X274803Y-372941D02*
Y-371941D01*
X266429Y-385039D02*
X267429D01*
X266929Y-385539D02*
Y-384539D01*
X243201Y-389370D02*
X244201D01*
X243701Y-389870D02*
Y-388870D01*
X249894Y-384646D02*
X250894D01*
X250394Y-385146D02*
Y-384146D01*
X227453Y-383858D02*
X228453D01*
X227953Y-384358D02*
Y-383358D01*
X233358Y-384646D02*
X234358D01*
X233858Y-385146D02*
Y-384146D01*
X212886Y-384646D02*
X213886D01*
X213386Y-385146D02*
Y-384146D01*
X512986Y-199213D02*
X513786D01*
X513386Y-199613D02*
Y-198813D01*
X521253Y-198819D02*
X522053D01*
X521654Y-199219D02*
Y-198419D01*
X590939Y-189764D02*
X591739D01*
X591339Y-190164D02*
Y-189364D01*
X152825Y-121747D02*
X153625D01*
X153225Y-122147D02*
Y-121347D01*
X132699Y-136519D02*
X133499D01*
X133099Y-136919D02*
Y-136119D01*
X24000Y-8429D02*
X25000D01*
X24500Y-8929D02*
Y-7929D01*
X602750Y-235946D02*
X603550D01*
X603150Y-236346D02*
Y-235546D01*
X603916Y-246600D02*
X604716D01*
X604316Y-247000D02*
Y-246199D01*
X152356Y-65354D02*
X153156D01*
X152756Y-65754D02*
Y-64954D01*
X152356Y-57480D02*
X153156D01*
X152756Y-57880D02*
Y-57080D01*
X152356Y-49606D02*
X153156D01*
X152756Y-50006D02*
Y-49206D01*
X157080Y-73228D02*
X157880D01*
X157480Y-73628D02*
Y-72828D01*
X284246Y-291732D02*
X285046D01*
X284646Y-292132D02*
Y-291332D01*
X381490Y-183858D02*
X382290D01*
X381890Y-184258D02*
Y-183458D01*
X384246Y-184252D02*
X385046D01*
X384646Y-184652D02*
Y-183852D01*
X359343Y-161024D02*
X360343D01*
X359842Y-161524D02*
Y-160524D01*
X362886Y-160630D02*
X363886D01*
X363386Y-161130D02*
Y-160130D01*
X367216Y-160630D02*
X368216D01*
X367717Y-161130D02*
Y-160130D01*
X454375Y-308565D02*
X455175D01*
X454775Y-308965D02*
Y-308166D01*
X569285Y-303150D02*
X570085D01*
X569685Y-303550D02*
Y-302750D01*
X607868Y-84252D02*
X608668D01*
X608268Y-84652D02*
Y-83852D01*
X382683Y-161839D02*
X383483D01*
X383083Y-162239D02*
Y-161439D01*
X420913Y-174784D02*
X421713D01*
X421313Y-175184D02*
Y-174384D01*
X396450Y-249016D02*
X397250D01*
X396850Y-249416D02*
Y-248616D01*
X128663Y-136618D02*
X129463D01*
X129063Y-137018D02*
Y-136218D01*
X38213Y-53355D02*
X39013D01*
X38613Y-53755D02*
Y-52955D01*
X172274Y-138386D02*
X173074D01*
X172674Y-138786D02*
Y-137986D01*
X613005Y-89494D02*
X613805D01*
X613406Y-89894D02*
Y-89094D01*
X387789Y-162205D02*
X388589D01*
X388189Y-162605D02*
Y-161805D01*
X419398Y-176745D02*
X420198D01*
X419798Y-177145D02*
Y-176345D01*
X401175Y-249213D02*
X401975D01*
X401575Y-249613D02*
Y-248813D01*
X125908Y-136224D02*
X126707D01*
X126307Y-136624D02*
Y-135824D01*
X38183Y-58355D02*
X38983D01*
X38583Y-58755D02*
Y-57955D01*
X169912Y-139961D02*
X170712D01*
X170311Y-140361D02*
Y-139561D01*
X491232Y-149213D02*
X492232D01*
X491732Y-149713D02*
Y-148713D01*
X499894Y-145669D02*
X500894D01*
X500394Y-146169D02*
Y-145169D01*
X495563Y-145276D02*
X496563D01*
X496063Y-145776D02*
Y-144776D01*
X491232Y-145276D02*
X492232D01*
X491732Y-145776D02*
Y-144776D01*
X549991Y-243310D02*
X550791D01*
X550391Y-243710D02*
Y-242910D01*
X476765Y-247244D02*
X477565D01*
X477165Y-247644D02*
Y-246844D01*
X538870Y-228740D02*
X539870D01*
X539370Y-229240D02*
Y-228240D01*
X542413Y-228740D02*
X543413D01*
X542913Y-229240D02*
Y-228240D01*
X560524Y-183465D02*
X561524D01*
X561024Y-183965D02*
Y-182965D01*
X560524Y-186614D02*
X561524D01*
X561024Y-187114D02*
Y-186114D01*
X-5124Y-283071D02*
X-4324D01*
X-4724Y-283471D02*
Y-282671D01*
X34933Y-129528D02*
X35933D01*
X35433Y-130028D02*
Y-129028D01*
X31784Y-129528D02*
X32783D01*
X32283Y-130028D02*
Y-129028D01*
X28240Y-129528D02*
X29240D01*
X28740Y-130028D02*
Y-129028D01*
X35033Y-50787D02*
X35833D01*
X35433Y-51187D02*
Y-50387D01*
X149535Y-124206D02*
X150335D01*
X149935Y-124606D02*
Y-123805D01*
X149833Y-119882D02*
X150633D01*
X150233Y-120282D02*
Y-119482D01*
X429128Y-231496D02*
X429928D01*
X429528Y-231896D02*
Y-231096D01*
X363773Y-280315D02*
X364573D01*
X364173Y-280715D02*
Y-279915D01*
X461805Y-255118D02*
X462605D01*
X462205Y-255518D02*
Y-254718D01*
X464561Y-125197D02*
X465361D01*
X464961Y-125597D02*
Y-124797D01*
X49600Y-44094D02*
X50400D01*
X50000Y-44495D02*
Y-43694D01*
X323516Y-42913D02*
X324516D01*
X324016Y-43413D02*
Y-42413D01*
X318398Y-43307D02*
X319398D01*
X318898Y-43807D02*
Y-42807D01*
X323516Y-39764D02*
X324516D01*
X324016Y-40264D02*
Y-39264D01*
X318398Y-39764D02*
X319398D01*
X318898Y-40264D02*
Y-39264D01*
X323516Y-35827D02*
X324516D01*
X324016Y-36327D02*
Y-35327D01*
X318398Y-35827D02*
X319398D01*
X318898Y-36327D02*
Y-35327D01*
X504618Y-24016D02*
X505618D01*
X505118Y-24516D02*
Y-23516D01*
X500287Y-24409D02*
X501287D01*
X500787Y-24909D02*
Y-23910D01*
X495957Y-24016D02*
X496957D01*
X496457Y-24516D02*
Y-23516D01*
X504618Y-20079D02*
X505618D01*
X505118Y-20579D02*
Y-19579D01*
X500287Y-20079D02*
X501287D01*
X500787Y-20579D02*
Y-19579D01*
X495957Y-20079D02*
X496957D01*
X496457Y-20579D02*
Y-19579D01*
X245169Y-74016D02*
X246169D01*
X245669Y-74516D02*
Y-73516D01*
X245563Y-70079D02*
X246563D01*
X246063Y-70579D02*
Y-69579D01*
X241232Y-74016D02*
X242232D01*
X241732Y-74516D02*
Y-73516D01*
X241232Y-70079D02*
X242232D01*
X241732Y-70579D02*
Y-69579D01*
X326272Y-73622D02*
X327272D01*
X326772Y-74122D02*
Y-73122D01*
X321941Y-73622D02*
X322941D01*
X322441Y-74122D02*
Y-73122D01*
X317216Y-73228D02*
X318216D01*
X317717Y-73728D02*
Y-72728D01*
X326272Y-69291D02*
X327272D01*
X326772Y-69791D02*
Y-68791D01*
X321941Y-69291D02*
X322941D01*
X322441Y-69791D02*
Y-68791D01*
X317216Y-69291D02*
X318216D01*
X317717Y-69791D02*
Y-68791D01*
X427553Y-206299D02*
X428353D01*
X427953Y-206699D02*
Y-205899D01*
X481096Y-197244D02*
X481896D01*
X481496Y-197644D02*
Y-196844D01*
X468004Y-44488D02*
X469004D01*
X468504Y-44988D02*
Y-43988D01*
X463279Y-44488D02*
X464280D01*
X463779Y-44988D02*
Y-43988D01*
X458161Y-44094D02*
X459161D01*
X458661Y-44594D02*
Y-43595D01*
X468398Y-39764D02*
X469398D01*
X468898Y-40264D02*
Y-39264D01*
X463279Y-39370D02*
X464280D01*
X463779Y-39870D02*
Y-38870D01*
X458161Y-39370D02*
X459161D01*
X458661Y-39870D02*
Y-38870D01*
X295169Y-45276D02*
X296169D01*
X295669Y-45776D02*
Y-44776D01*
X290445Y-45276D02*
X291445D01*
X290945Y-45776D02*
Y-44776D01*
X294776Y-40945D02*
X295776D01*
X295276Y-41445D02*
Y-40445D01*
X290445Y-40945D02*
X291445D01*
X290945Y-41445D02*
Y-40445D01*
X294776Y-35433D02*
X295776D01*
X295276Y-35933D02*
Y-34933D01*
X290445Y-35433D02*
X291445D01*
X290945Y-35933D02*
Y-34933D01*
X118104Y-40945D02*
X118904D01*
X118504Y-41345D02*
Y-40545D01*
X84539Y-77559D02*
X85539D01*
X85039Y-78059D02*
Y-77059D01*
X383065Y-234252D02*
X383865D01*
X383465Y-234652D02*
Y-233852D01*
X389364Y-234252D02*
X390164D01*
X389764Y-234652D02*
Y-233852D01*
X386214Y-237402D02*
X387014D01*
X386614Y-237802D02*
Y-237002D01*
X386214Y-231102D02*
X387014D01*
X386614Y-231502D02*
Y-230702D01*
X611411Y-221260D02*
X612211D01*
X611811Y-221660D02*
Y-220860D01*
X426372Y-179528D02*
X427172D01*
X426772Y-179928D02*
Y-179128D01*
X418498Y-245276D02*
X419298D01*
X418898Y-245676D02*
Y-244876D01*
X601705Y-99109D02*
X602505D01*
X602105Y-99509D02*
Y-98709D01*
X596844Y-108661D02*
X597644D01*
X597244Y-109061D02*
Y-108261D01*
X592513Y-116535D02*
X593313D01*
X592913Y-116935D02*
Y-116135D01*
X594088Y-132677D02*
X594888D01*
X594488Y-133077D02*
Y-132277D01*
X43301Y-34646D02*
X44101D01*
X43701Y-35046D02*
Y-34246D01*
X50887Y-126878D02*
X51687D01*
X51287Y-127278D02*
Y-126478D01*
X12986Y-126878D02*
X13786D01*
X13386Y-127278D02*
Y-126478D01*
X29143Y-345214D02*
X29943D01*
X29543Y-345614D02*
Y-344814D01*
X239757Y-278740D02*
X240558D01*
X240158Y-279140D02*
Y-278340D01*
X25878Y-20472D02*
X26878D01*
X26378Y-20972D02*
Y-19972D01*
X23910Y-16535D02*
X24909D01*
X24409Y-17035D02*
Y-16035D01*
X25878Y-10630D02*
X26878D01*
X26378Y-11130D02*
Y-10130D01*
X35033Y15354D02*
X35833D01*
X35433Y14954D02*
Y15754D01*
X35820Y8268D02*
X36621D01*
X36220Y7868D02*
Y8668D01*
X35427Y1575D02*
X36227D01*
X35827Y1175D02*
Y1975D01*
X19285Y-2362D02*
X20085D01*
X19685Y-2762D02*
Y-1962D01*
X19679Y3937D02*
X20479D01*
X20079Y3537D02*
Y4337D01*
X19679Y10630D02*
X20479D01*
X20079Y10230D02*
Y11030D01*
X19679Y17323D02*
X20479D01*
X20079Y16923D02*
Y17723D01*
X298419Y-269685D02*
X299219D01*
X298819Y-270085D02*
Y-269285D01*
X390939Y-277953D02*
X391739D01*
X391339Y-278353D02*
Y-277553D01*
X299206Y-185433D02*
X300006D01*
X299606Y-185833D02*
Y-185033D01*
X230702Y-239764D02*
X231502D01*
X231102Y-240164D02*
Y-239364D01*
X230309Y-242913D02*
X231109D01*
X230709Y-243313D02*
Y-242513D01*
X398813Y-193307D02*
X399613D01*
X399213Y-193707D02*
Y-192907D01*
X203931Y-101575D02*
X204731D01*
X204331Y-101975D02*
Y-101175D01*
X431883Y-254724D02*
X432684D01*
X432283Y-255124D02*
Y-254324D01*
X495663Y-244094D02*
X496463D01*
X496063Y-244495D02*
Y-243694D01*
X172828Y-117323D02*
X173628D01*
X173228Y-117723D02*
Y-116923D01*
X260624Y-200394D02*
X261424D01*
X261024Y-200794D02*
Y-199994D01*
X381490Y-254331D02*
X382290D01*
X381890Y-254731D02*
Y-253931D01*
X318589Y-253024D02*
X319389D01*
X318989Y-253424D02*
Y-252624D01*
X337002Y-260630D02*
X337802D01*
X337402Y-261030D02*
Y-260230D01*
X428734Y-246850D02*
X429534D01*
X429134Y-247250D02*
Y-246450D01*
X483431Y-241339D02*
X484231D01*
X483831Y-241739D02*
Y-240939D01*
X487789Y-216535D02*
X488589D01*
X488189Y-216935D02*
Y-216135D01*
X500571Y-219896D02*
X501371D01*
X500971Y-220296D02*
Y-219496D01*
X470072Y-246457D02*
X470872D01*
X470472Y-246857D02*
Y-246057D01*
X476569Y-76378D02*
X477368D01*
X476968Y-76778D02*
Y-75978D01*
X462592Y-76378D02*
X463392D01*
X462992Y-76778D02*
Y-75978D01*
X288970Y-205906D02*
X289770D01*
X289370Y-206306D02*
Y-205505D01*
X343301Y-200394D02*
X344101D01*
X343701Y-200794D02*
Y-199994D01*
X357080Y-214567D02*
X357880D01*
X357480Y-214967D02*
Y-214167D01*
X152750Y-113386D02*
X153550D01*
X153150Y-113786D02*
Y-112986D01*
X225978Y-32677D02*
X226778D01*
X226378Y-33077D02*
Y-32277D01*
X99994Y-30315D02*
X100794D01*
X100394Y-30715D02*
Y-29915D01*
X382671Y-276772D02*
X383471D01*
X383071Y-277172D02*
Y-276372D01*
X402356Y-281102D02*
X403156D01*
X402756Y-281502D02*
Y-280702D01*
X616529Y-225984D02*
X617329D01*
X616929Y-226384D02*
Y-225584D01*
X611214Y-186107D02*
X612014D01*
X611614Y-186507D02*
Y-185707D01*
X585820Y-178740D02*
X586621D01*
X586221Y-179140D02*
Y-178340D01*
X590939Y-144488D02*
X591739D01*
X591339Y-144888D02*
Y-144088D01*
X586214Y-158661D02*
X587014D01*
X586614Y-159061D02*
Y-158261D01*
X581765Y-163898D02*
X582565D01*
X582165Y-164298D02*
Y-163498D01*
X581490Y-174016D02*
X582290D01*
X581890Y-174416D02*
Y-173616D01*
X578734Y-214006D02*
X579534D01*
X579134Y-214406D02*
Y-213606D01*
X581490Y-235925D02*
X582290D01*
X581890Y-236325D02*
Y-235525D01*
X584246Y-225197D02*
X585046D01*
X584646Y-225597D02*
Y-224797D01*
X589788Y-221161D02*
X590588D01*
X590188Y-221561D02*
Y-220761D01*
X608261Y-220472D02*
X609061D01*
X608661Y-220872D02*
Y-220072D01*
X588970Y-212992D02*
X589770D01*
X589370Y-213392D02*
Y-212592D01*
X588522Y-206462D02*
X589322D01*
X588922Y-206862D02*
Y-206062D01*
X583458Y-192913D02*
X584258D01*
X583858Y-193313D02*
Y-192513D01*
X588970Y-201575D02*
X589770D01*
X589370Y-201975D02*
Y-201175D01*
X329128Y-181890D02*
X329928D01*
X329528Y-182290D02*
Y-181490D01*
X306687Y-198819D02*
X307487D01*
X307087Y-199219D02*
Y-198419D01*
X278734Y-230315D02*
X279534D01*
X279134Y-230715D02*
Y-229915D01*
X279915Y-226378D02*
X280715D01*
X280315Y-226778D02*
Y-225978D01*
X276765Y-236221D02*
X277565D01*
X277165Y-236620D02*
Y-235821D01*
X281096Y-237402D02*
X281896D01*
X281496Y-237802D02*
Y-237002D01*
X27159Y-337402D02*
X27959D01*
X27559Y-337802D02*
Y-337002D01*
X288183Y-237402D02*
X288983D01*
X288583Y-237802D02*
Y-237002D01*
X292907Y-237008D02*
X293707D01*
X293307Y-237408D02*
Y-236608D01*
X340939Y-277953D02*
X341739D01*
X341339Y-278353D02*
Y-277553D01*
X407474Y-216535D02*
X408274D01*
X407874Y-216935D02*
Y-216135D01*
X408360Y-238189D02*
X409160D01*
X408760Y-238589D02*
Y-237789D01*
X462073Y-277635D02*
X462873D01*
X462473Y-278035D02*
Y-277235D01*
X321450Y-283465D02*
X322250D01*
X321850Y-283865D02*
Y-283065D01*
X461017Y-305118D02*
X461817D01*
X461417Y-305518D02*
Y-304718D01*
X343301Y-209449D02*
X344101D01*
X343701Y-209849D02*
Y-209049D01*
X347238Y-202756D02*
X348038D01*
X347638Y-203156D02*
Y-202356D01*
X382671Y-168110D02*
X383471D01*
X383071Y-168510D02*
Y-167710D01*
X597997Y-88288D02*
X598797D01*
X598397Y-88687D02*
Y-87888D01*
X603143Y-87795D02*
X603943D01*
X603543Y-88195D02*
Y-87395D01*
X135033Y-79134D02*
X135833D01*
X135433Y-79534D02*
Y-78734D01*
X424010Y-205512D02*
X424810D01*
X424409Y-205912D02*
Y-205112D01*
X427947Y-187795D02*
X428747D01*
X428346Y-188195D02*
Y-187395D01*
X139670Y-132385D02*
X140470D01*
X140070Y-132785D02*
Y-131985D01*
X139716Y-124048D02*
X140516D01*
X140116Y-124448D02*
Y-123648D01*
X140939Y394D02*
X141739D01*
X141339Y-6D02*
Y794D01*
X180210Y-87795D02*
X181010D01*
X180610Y-88195D02*
Y-87395D01*
X198124Y-87795D02*
X198924D01*
X198524Y-88195D02*
Y-87395D01*
X196844Y-102756D02*
X197644D01*
X197244Y-103156D02*
Y-102356D01*
X180604Y-101181D02*
X181404D01*
X181004Y-101581D02*
Y-100781D01*
X177159Y-87795D02*
X177959D01*
X177559Y-88195D02*
Y-87395D01*
X197238Y-97638D02*
X198038D01*
X197638Y-98038D02*
Y-97238D01*
X181884Y-97244D02*
X182684D01*
X182283Y-97644D02*
Y-96844D01*
X182277Y-94488D02*
X183077D01*
X182677Y-94888D02*
Y-94088D01*
X189364Y-88189D02*
X190164D01*
X189764Y-88589D02*
Y-87789D01*
X189364Y-100787D02*
X190164D01*
X189764Y-101187D02*
Y-100387D01*
X196450Y-94488D02*
X197250D01*
X196850Y-94888D02*
Y-94088D01*
X161017Y-25984D02*
X161817D01*
X161417Y-26384D02*
Y-25584D01*
X168891Y13386D02*
X169691D01*
X169291Y12986D02*
Y13786D01*
X168891Y9646D02*
X169691D01*
X169291Y9246D02*
Y10046D01*
X159442Y9646D02*
X160242D01*
X159843Y9246D02*
Y10046D01*
X150781Y14173D02*
X151581D01*
X151181Y13773D02*
Y14573D01*
X142120Y13189D02*
X142920D01*
X142520Y12789D02*
Y13589D01*
X144285Y-11811D02*
X145085D01*
X144685Y-12211D02*
Y-11411D01*
X162198Y-9449D02*
X162998D01*
X162598Y-9849D02*
Y-9049D01*
X153143Y-10433D02*
X153943D01*
X153543Y-10833D02*
Y-10033D01*
X162198Y-13189D02*
X162998D01*
X162598Y-13589D02*
Y-12789D01*
X162198Y-1575D02*
X162998D01*
X162598Y-1975D02*
Y-1175D01*
X150781Y18110D02*
X151581D01*
X151181Y17710D02*
Y18510D01*
X137198Y-6299D02*
X137998D01*
X137598Y-6699D02*
Y-5899D01*
X133655Y-6299D02*
X134455D01*
X134055Y-6699D02*
Y-5899D01*
X149403Y-9238D02*
X150203D01*
X149803Y-9638D02*
Y-8838D01*
X149500Y-787D02*
X150500D01*
X150000Y-1287D02*
Y-287D01*
X151382Y10443D02*
X152182D01*
X151782Y10043D02*
Y10843D01*
X472903Y-276476D02*
X473703D01*
X473303Y-276876D02*
Y-276076D01*
X478931Y-294626D02*
X479731D01*
X479331Y-295026D02*
Y-294226D01*
X487002Y-256988D02*
X487802D01*
X487402Y-257388D02*
Y-256588D01*
X485427Y-279429D02*
X486227D01*
X485827Y-279829D02*
Y-279029D01*
X476372Y-254035D02*
X477172D01*
X476772Y-254435D02*
Y-253635D01*
X473222Y-259055D02*
X474022D01*
X473622Y-259455D02*
Y-258655D01*
X475978Y-273622D02*
X476778D01*
X476378Y-274022D02*
Y-273222D01*
X485820Y-265748D02*
X486621D01*
X486221Y-266148D02*
Y-265348D01*
X474010Y-265748D02*
X474810D01*
X474409Y-266148D02*
Y-265348D01*
X479915Y-259744D02*
X480715D01*
X480315Y-260144D02*
Y-259344D01*
X479915Y-271752D02*
X480715D01*
X480315Y-272152D02*
Y-271352D01*
X548419Y-300787D02*
X549219D01*
X548819Y-301187D02*
Y-300387D01*
X489167Y-310236D02*
X489967D01*
X489567Y-310636D02*
Y-309836D01*
X491923Y-303543D02*
X492723D01*
X492323Y-303943D02*
Y-303143D01*
X495466Y-303543D02*
X496266D01*
X495866Y-303943D02*
Y-303143D01*
X483065Y-291535D02*
X483865D01*
X483465Y-291935D02*
Y-291135D01*
X476372Y-291929D02*
X477172D01*
X476772Y-292329D02*
Y-291529D01*
X465742Y-294685D02*
X466542D01*
X466142Y-295085D02*
Y-294285D01*
X465742Y-298228D02*
X466542D01*
X466142Y-298628D02*
Y-297828D01*
X461017Y-312099D02*
X461817D01*
X461417Y-312498D02*
Y-311699D01*
X473419Y-315354D02*
X474219D01*
X473819Y-315754D02*
Y-314954D01*
X484443Y-317717D02*
X485243D01*
X484842Y-318116D02*
Y-317317D01*
X492710Y-310236D02*
X493510D01*
X493110Y-310636D02*
Y-309836D01*
X460624Y-302756D02*
X461424D01*
X461024Y-303156D02*
Y-302356D01*
X498025Y-307087D02*
X498825D01*
X498425Y-307487D02*
Y-306687D01*
X477846Y-305118D02*
X478847D01*
X478346Y-305618D02*
Y-304618D01*
X476962Y-313767D02*
X477762D01*
X477362Y-314167D02*
Y-313367D01*
X596464Y-266396D02*
X597264D01*
X596865Y-266796D02*
Y-265996D01*
X594365Y-266396D02*
X595164D01*
X594765Y-266796D02*
Y-265996D01*
X624538Y-196373D02*
X625338D01*
X624938Y-196773D02*
Y-195973D01*
X624526Y-201353D02*
X625326D01*
X624926Y-201753D02*
Y-200953D01*
X624538Y-206373D02*
X625338D01*
X624938Y-206773D02*
Y-205973D01*
X624518Y-211353D02*
X625318D01*
X624918Y-211753D02*
Y-210953D01*
X624679Y-173898D02*
X625479D01*
X625079Y-174298D02*
Y-173498D01*
X624285Y-163898D02*
X625085D01*
X624685Y-164298D02*
Y-163498D01*
X551569Y-297638D02*
X552368D01*
X551968Y-298038D02*
Y-297238D01*
X126765Y-12598D02*
X127565D01*
X127165Y-12998D02*
Y-12198D01*
X117710Y-36220D02*
X118510D01*
X118110Y-36621D02*
Y-35820D01*
X117316Y-47293D02*
X118116D01*
X117717Y-47693D02*
Y-46893D01*
X121254Y-52756D02*
X122054D01*
X121653Y-53156D02*
Y-52356D01*
X121254Y-31496D02*
X122054D01*
X121653Y-31896D02*
Y-31096D01*
X403993Y-224149D02*
X404993D01*
X404493Y-224649D02*
Y-223649D01*
X404126Y-219685D02*
X405126D01*
X404626Y-220185D02*
Y-219185D01*
X577932Y-261235D02*
X578732D01*
X578332Y-261635D02*
Y-260835D01*
X507474Y-255906D02*
X508274D01*
X507874Y-256306D02*
Y-255505D01*
X534414Y-297190D02*
X535214D01*
X534814Y-297590D02*
Y-296790D01*
X528560Y-296841D02*
X529360D01*
X528960Y-297241D02*
Y-296441D01*
X494876Y-298130D02*
X495676D01*
X495276Y-298530D02*
Y-297730D01*
X502947Y-297967D02*
X503747D01*
X503346Y-298367D02*
Y-297567D01*
X507080Y-298130D02*
X507880D01*
X507480Y-298530D02*
Y-297730D01*
X500781Y-298130D02*
X501581D01*
X501181Y-298530D02*
Y-297730D01*
X516529Y-298130D02*
X517329D01*
X516929Y-298530D02*
Y-297730D01*
X522435Y-297736D02*
X523235D01*
X522835Y-298136D02*
Y-297336D01*
X540545Y-297342D02*
X541345D01*
X540945Y-297743D02*
Y-296942D01*
X546057Y-297342D02*
X546857D01*
X546457Y-297743D02*
Y-296942D01*
X561805Y-297736D02*
X562605D01*
X562205Y-298136D02*
Y-297336D01*
X567710Y-297736D02*
X568510D01*
X568110Y-298136D02*
Y-297336D01*
X570072Y-297736D02*
X570872D01*
X570472Y-298136D02*
Y-297336D01*
X575978Y-297736D02*
X576778D01*
X576378Y-298136D02*
Y-297336D01*
X570860Y-256791D02*
X571660D01*
X571260Y-257191D02*
Y-256391D01*
X568498Y-256791D02*
X569298D01*
X568898Y-257191D02*
Y-256391D01*
X549600Y-255610D02*
X550400D01*
X550000Y-256010D02*
Y-255210D01*
X540545Y-256004D02*
X541345D01*
X540945Y-256404D02*
Y-255604D01*
X538576Y-250886D02*
X539376D01*
X538976Y-251286D02*
Y-250486D01*
X536214Y-245374D02*
X537014D01*
X536614Y-245774D02*
Y-244974D01*
X517710Y-255217D02*
X518510D01*
X518110Y-255616D02*
Y-254817D01*
X521647Y-249705D02*
X522447D01*
X522047Y-250105D02*
Y-249305D01*
X523616Y-243799D02*
X524416D01*
X524016Y-244199D02*
Y-243399D01*
X501962Y-257185D02*
X502762D01*
X502362Y-257585D02*
Y-256785D01*
X503931Y-257185D02*
X504731D01*
X504331Y-257585D02*
Y-256785D01*
X512986Y-254429D02*
X513786D01*
X513386Y-254829D02*
Y-254029D01*
X507868Y-251673D02*
X508668D01*
X508268Y-252073D02*
Y-251273D01*
X563773Y-255906D02*
X564573D01*
X564173Y-256306D02*
Y-255505D01*
X494482Y-262303D02*
X495282D01*
X494882Y-262703D02*
Y-261903D01*
X495269Y-255512D02*
X496069D01*
X495669Y-255912D02*
Y-255112D01*
X209049Y7087D02*
X209849D01*
X209449Y6687D02*
Y7487D01*
X203537Y1969D02*
X204337D01*
X203937Y1568D02*
Y2369D01*
X213773Y1181D02*
X214573D01*
X214173Y781D02*
Y1581D01*
X213773Y-79134D02*
X214573D01*
X214173Y-79534D02*
Y-78734D01*
X204718Y-79380D02*
X205518D01*
X205118Y-79780D02*
Y-78980D01*
X214167Y-11417D02*
X214967D01*
X214567Y-11817D02*
Y-11017D01*
X211411Y-16535D02*
X212211D01*
X211811Y-16935D02*
Y-16135D01*
X208655Y-7480D02*
X209455D01*
X209055Y-7880D02*
Y-7080D01*
X208655Y-5512D02*
X209455D01*
X209055Y-5912D02*
Y-5112D01*
X209049Y-3543D02*
X209849D01*
X209449Y-3943D02*
Y-3143D01*
X216135Y-25197D02*
X216935D01*
X216535Y-25597D02*
Y-24797D01*
X210624Y-21260D02*
X211424D01*
X211024Y-21660D02*
Y-20860D01*
X220466Y-39764D02*
X221266D01*
X220866Y-40164D02*
Y-39364D01*
X214954Y-42126D02*
X215754D01*
X215354Y-42526D02*
Y-41726D01*
X209836Y-44094D02*
X210636D01*
X210236Y-44495D02*
Y-43694D01*
X210230Y-53150D02*
X211030D01*
X210630Y-53550D02*
Y-52750D01*
X209141Y-58689D02*
X209941D01*
X209541Y-59089D02*
Y-58289D01*
X209049Y-72047D02*
X209849D01*
X209449Y-72447D02*
Y-71647D01*
X209049Y-74410D02*
X209849D01*
X209449Y-74809D02*
Y-74010D01*
X168104Y-79528D02*
X168904D01*
X168504Y-79928D02*
Y-79128D01*
X168104Y-73622D02*
X168904D01*
X168504Y-74022D02*
Y-73222D01*
X168104Y-71260D02*
X168904D01*
X168504Y-71660D02*
Y-70860D01*
X168104Y-65354D02*
X168904D01*
X168504Y-65754D02*
Y-64954D01*
X168498Y-49606D02*
X169298D01*
X168898Y-50006D02*
Y-49206D01*
X168498Y-44094D02*
X169298D01*
X168898Y-44495D02*
Y-43694D01*
X168104Y-37795D02*
X168904D01*
X168504Y-38195D02*
Y-37395D01*
X168104Y-31890D02*
X168904D01*
X168504Y-32290D02*
Y-31490D01*
X168104Y-25984D02*
X168904D01*
X168504Y-26384D02*
Y-25584D01*
X167710Y-20079D02*
X168510D01*
X168110Y-20479D02*
Y-19679D01*
X167710Y-4331D02*
X168510D01*
X168110Y-4731D02*
Y-3931D01*
X167710Y-10630D02*
X168510D01*
X168110Y-11030D02*
Y-10230D01*
X167873Y-6496D02*
X168673D01*
X168273Y-6896D02*
Y-6096D01*
X167710Y1575D02*
X168510D01*
X168110Y1175D02*
Y1975D01*
X100681Y-38583D02*
X101681D01*
X101181Y-39083D02*
Y-38083D01*
X143694Y-80315D02*
X144494D01*
X144095Y-80715D02*
Y-79915D01*
X149206Y-80315D02*
X150006D01*
X149606Y-80715D02*
Y-79915D01*
X116923Y-65354D02*
X117723D01*
X117323Y-65754D02*
Y-64954D01*
X121067Y-74575D02*
X121867D01*
X121467Y-74975D02*
Y-74174D01*
X-19001Y-349409D02*
X-18201D01*
X-18601Y-349809D02*
Y-349009D01*
X87395Y-99606D02*
X88195D01*
X87795Y-100006D02*
Y-99206D01*
X540151Y-340945D02*
X540951D01*
X540551Y-341345D02*
Y-340545D01*
X535427Y-345276D02*
X536227D01*
X535827Y-345676D02*
Y-344876D01*
X555112Y-340158D02*
X555912D01*
X555512Y-340558D02*
Y-339757D01*
X544482Y-336221D02*
X545282D01*
X544882Y-336620D02*
Y-335821D01*
X552356Y-335827D02*
X553156D01*
X552756Y-336227D02*
Y-335427D01*
X560624Y-340158D02*
X561424D01*
X561024Y-340558D02*
Y-339757D01*
X568498Y-319009D02*
X569298D01*
X568898Y-319409D02*
Y-318609D01*
X569679Y-309921D02*
X570479D01*
X570079Y-310321D02*
Y-309521D01*
X552356Y-305118D02*
X553156D01*
X552756Y-305518D02*
Y-304718D01*
X544482Y-305118D02*
X545282D01*
X544882Y-305518D02*
Y-304718D01*
X535820Y-300787D02*
X536621D01*
X536221Y-301187D02*
Y-300387D01*
X530309Y-300787D02*
X531109D01*
X530709Y-301187D02*
Y-300387D01*
X529915Y-338976D02*
X530715D01*
X530315Y-339376D02*
Y-338576D01*
X513006Y-302902D02*
X513806D01*
X513406Y-303302D02*
Y-302502D01*
X521253Y-336221D02*
X522053D01*
X521654Y-336620D02*
Y-335821D01*
X512986Y-336221D02*
X513786D01*
X513386Y-336620D02*
Y-335821D01*
X505010Y-336036D02*
X505810D01*
X505410Y-336436D02*
Y-335636D01*
X505112Y-303150D02*
X505912D01*
X505512Y-303550D02*
Y-302750D01*
X454618Y-92520D02*
X455618D01*
X455118Y-93020D02*
Y-92020D01*
X459736Y-87795D02*
X460736D01*
X460236Y-88295D02*
Y-87295D01*
X459736Y-92520D02*
X460736D01*
X460236Y-93020D02*
Y-92020D01*
X454224Y-87795D02*
X455224D01*
X454724Y-88295D02*
Y-87295D01*
X623910Y-31496D02*
X624909D01*
X624409Y-31996D02*
Y-30996D01*
X619579Y-31890D02*
X620579D01*
X620079Y-32390D02*
Y-31390D01*
X615248Y-32283D02*
X616248D01*
X615748Y-32783D02*
Y-31784D01*
X610917Y-33071D02*
X611917D01*
X611417Y-33571D02*
Y-32571D01*
X620366Y-35827D02*
X621366D01*
X620866Y-36327D02*
Y-35327D01*
X611311Y-38189D02*
X612311D01*
X611811Y-38689D02*
Y-37689D01*
X600681Y-23622D02*
X601681D01*
X601181Y-24122D02*
Y-23122D01*
X596744Y-23622D02*
X597744D01*
X597244Y-24122D02*
Y-23122D01*
X596744Y-29921D02*
X597744D01*
X597244Y-30421D02*
Y-29421D01*
X600681Y-26772D02*
X601681D01*
X601181Y-27272D02*
Y-26272D01*
X600681Y-29921D02*
X601681D01*
X601181Y-30421D02*
Y-29421D01*
X596744Y-26772D02*
X597744D01*
X597244Y-27272D02*
Y-26272D01*
X542413Y-72835D02*
X543413D01*
X542913Y-73335D02*
Y-72335D01*
X542413Y-69291D02*
X543413D01*
X542913Y-69791D02*
Y-68791D01*
X542413Y-65748D02*
X543413D01*
X542913Y-66248D02*
Y-65248D01*
X542413Y-61811D02*
X543413D01*
X542913Y-62311D02*
Y-61311D01*
X542413Y-58268D02*
X543413D01*
X542913Y-58768D02*
Y-57768D01*
X594876Y-79921D02*
X595676D01*
X595276Y-80321D02*
Y-79521D01*
X608006Y-70079D02*
X608806D01*
X608405Y-70479D02*
Y-69679D01*
X617710Y-62205D02*
X618510D01*
X618110Y-62605D02*
Y-61805D01*
X615642Y-47638D02*
X616642D01*
X616142Y-48138D02*
Y-47138D01*
X618398Y-50787D02*
X619398D01*
X618898Y-51287D02*
Y-50287D01*
X612886Y-50787D02*
X613886D01*
X613386Y-51287D02*
Y-50287D01*
X609047Y-51181D02*
X610047D01*
X609547Y-51681D02*
Y-50681D01*
X606193Y-50787D02*
X607193D01*
X606693Y-51287D02*
Y-50287D01*
X601075Y-53543D02*
X602075D01*
X601575Y-54043D02*
Y-53043D01*
X598713Y-50000D02*
X599713D01*
X599213Y-50500D02*
Y-49500D01*
X543595Y-42126D02*
X544594D01*
X544095Y-42626D02*
Y-41626D01*
X539264Y-42126D02*
X540264D01*
X539764Y-42626D02*
Y-41626D01*
X534146Y-51968D02*
X535146D01*
X534646Y-52469D02*
Y-51468D01*
X533752Y-48425D02*
X534752D01*
X534252Y-48925D02*
Y-47925D01*
X534146Y-45276D02*
X535146D01*
X534646Y-45776D02*
Y-44776D01*
X534146Y-42126D02*
X535146D01*
X534646Y-42626D02*
Y-41626D01*
X237789Y-107087D02*
X238589D01*
X238189Y-107487D02*
Y-106687D01*
X232671Y-107087D02*
X233471D01*
X233071Y-107487D02*
Y-106687D01*
X222828Y-107480D02*
X223628D01*
X223228Y-107880D02*
Y-107080D01*
X227946Y-107480D02*
X228747D01*
X228346Y-107880D02*
Y-107080D01*
X237789Y-138976D02*
X238589D01*
X238189Y-139376D02*
Y-138576D01*
X232809Y-139232D02*
X233609D01*
X233209Y-139632D02*
Y-138832D01*
X227809Y-138721D02*
X228609D01*
X228209Y-139120D02*
Y-138321D01*
X217005Y-138189D02*
X217805D01*
X217405Y-138589D02*
Y-137789D01*
X222809Y-137815D02*
X223609D01*
X223209Y-138215D02*
Y-137415D01*
X213773Y-107087D02*
X214573D01*
X214173Y-107487D02*
Y-106687D01*
X191726Y-111811D02*
X192526D01*
X192126Y-112211D02*
Y-111411D01*
X198793Y-105925D02*
X199593D01*
X199193Y-106325D02*
Y-105525D01*
X203793Y-138257D02*
X204593D01*
X204193Y-138657D02*
Y-137857D01*
X198793Y-138680D02*
X199593D01*
X199193Y-139080D02*
Y-138280D01*
X129844Y-120870D02*
X130645D01*
X130245Y-121270D02*
Y-120470D01*
X132699Y-119984D02*
X133499D01*
X133099Y-120384D02*
Y-119584D01*
X148025Y-104336D02*
X148825D01*
X148425Y-104736D02*
Y-103936D01*
X152750Y-103412D02*
X153550D01*
X153150Y-103812D02*
Y-103012D01*
X152750Y-99691D02*
X153550D01*
X153150Y-100091D02*
Y-99291D01*
X157868Y-107480D02*
X158668D01*
X158268Y-107880D02*
Y-107080D01*
X167710Y-103937D02*
X168510D01*
X168110Y-104337D02*
Y-103537D01*
X167710Y-100132D02*
X168510D01*
X168110Y-100532D02*
Y-99732D01*
X161017Y-95276D02*
X161817D01*
X161417Y-95676D02*
Y-94876D01*
X161017Y-107480D02*
X161817D01*
X161417Y-107880D02*
Y-107080D01*
X121292Y-94557D02*
X133492D01*
X127392Y-100657D02*
Y-88457D01*
X359481Y7806D02*
X371681D01*
X365581Y1705D02*
Y13905D01*
X359481Y-94557D02*
X371681D01*
X365581Y-100657D02*
Y-88457D01*
X121292Y7806D02*
X133492D01*
X127392Y1705D02*
Y13905D01*
X177786Y-136811D02*
X178586D01*
X178185Y-137211D02*
Y-136411D01*
X177786Y-133661D02*
X178586D01*
X178185Y-134061D02*
Y-133261D01*
X150226Y-130512D02*
X151026D01*
X150627Y-130912D02*
Y-130112D01*
X149833Y-127362D02*
X150633D01*
X150233Y-127762D02*
Y-126962D01*
X152504Y-124213D02*
X153304D01*
X152904Y-124613D02*
Y-123813D01*
X151998Y-117717D02*
X152798D01*
X152398Y-118116D02*
Y-117316D01*
X156526Y-111614D02*
X157326D01*
X156926Y-112014D02*
Y-111214D01*
X164443Y-114040D02*
X165243D01*
X164843Y-114439D02*
Y-113639D01*
X159675Y-112402D02*
X160475D01*
X160075Y-112802D02*
Y-112002D01*
X167943Y-110827D02*
X168743D01*
X168343Y-111227D02*
Y-110427D01*
X186447Y-135236D02*
X187247D01*
X186847Y-135636D02*
Y-134836D01*
X187628Y-113583D02*
X188428D01*
X188028Y-113983D02*
Y-113183D01*
X188709Y-131339D02*
X189709D01*
X189209Y-131839D02*
Y-130839D01*
X188709Y-117480D02*
X189709D01*
X189209Y-117980D02*
Y-116980D01*
X173061Y-127362D02*
X173861D01*
X173461Y-127762D02*
Y-126962D01*
X165187Y-139961D02*
X165987D01*
X165587Y-140361D02*
Y-139561D01*
X151408Y-137205D02*
X152208D01*
X151808Y-137605D02*
Y-136805D01*
X161841Y-140004D02*
X162641D01*
X162241Y-140404D02*
Y-139604D01*
X106193Y15354D02*
X107193D01*
X106693Y14854D02*
Y15854D01*
X106587Y9449D02*
X107587D01*
X107087Y8949D02*
Y9949D01*
X110524Y9449D02*
X111524D01*
X111024Y8949D02*
Y9949D01*
X110524Y15354D02*
X111524D01*
X111024Y14854D02*
Y15854D01*
X105012Y-79921D02*
X106012D01*
X105512Y-80421D02*
Y-79421D01*
X109343Y-79921D02*
X110343D01*
X109843Y-80421D02*
Y-79421D01*
X109343Y-74410D02*
X110343D01*
X109843Y-74910D02*
Y-73909D01*
X105012Y-74410D02*
X106012D01*
X105512Y-74910D02*
Y-73909D01*
X99106Y-63779D02*
X100106D01*
X99606Y-64280D02*
Y-63279D01*
X107374Y-63779D02*
X108374D01*
X107874Y-64280D02*
Y-63279D01*
X107374Y-59842D02*
X108374D01*
X107874Y-60343D02*
Y-59342D01*
X99106Y-59842D02*
X100106D01*
X99606Y-60343D02*
Y-59342D01*
X74116Y-61723D02*
X75116D01*
X74616Y-62223D02*
Y-61223D01*
X56293Y1060D02*
X57093D01*
X56693Y660D02*
Y1460D01*
X39264Y-29528D02*
X40264D01*
X39764Y-30028D02*
Y-29028D01*
X39264Y-25984D02*
X40264D01*
X39764Y-26484D02*
Y-25484D01*
X35231Y-9843D02*
X36231D01*
X35731Y-10343D02*
Y-9342D01*
X35231Y-18898D02*
X36231D01*
X35731Y-19398D02*
Y-18398D01*
X46941Y-27362D02*
X47941D01*
X47441Y-27862D02*
Y-26862D01*
X46941Y-21260D02*
X47941D01*
X47441Y-21760D02*
Y-20760D01*
X46941Y-5709D02*
X47941D01*
X47441Y-6209D02*
Y-5209D01*
X46941Y-11811D02*
X47941D01*
X47441Y-12311D02*
Y-11311D01*
X74894Y-5709D02*
X75894D01*
X75394Y-6209D02*
Y-5209D01*
X74894Y-11811D02*
X75894D01*
X75394Y-12311D02*
Y-11311D01*
X65642Y-11811D02*
X66642D01*
X66142Y-12311D02*
Y-11311D01*
X60917Y-11811D02*
X61917D01*
X61417Y-12311D02*
Y-11311D01*
X56193Y-11811D02*
X57193D01*
X56693Y-12311D02*
Y-11311D01*
X56193Y-16535D02*
X57193D01*
X56693Y-17035D02*
Y-16035D01*
X60917Y-16535D02*
X61917D01*
X61417Y-17035D02*
Y-16035D01*
X65642Y-16535D02*
X66642D01*
X66142Y-17035D02*
Y-16035D01*
X65642Y-21260D02*
X66642D01*
X66142Y-21760D02*
Y-20760D01*
X60917Y-21260D02*
X61917D01*
X61417Y-21760D02*
Y-20760D01*
X51962Y-35531D02*
X52762D01*
X52362Y-35932D02*
Y-35131D01*
X61017Y-35741D02*
X61817D01*
X61417Y-36141D02*
Y-35341D01*
X37002Y-43355D02*
X37802D01*
X37402Y-43755D02*
Y-42955D01*
X37982Y-48355D02*
X38782D01*
X38382Y-48755D02*
Y-47955D01*
X65702Y-64085D02*
X66502D01*
X66102Y-64485D02*
Y-63685D01*
X72395Y-53355D02*
X73194D01*
X72795Y-53755D02*
Y-52955D01*
X86114Y-56299D02*
X87114D01*
X86614Y-56799D02*
Y-55799D01*
X90839Y-35039D02*
X91839D01*
X91339Y-35539D02*
Y-34539D01*
X86114Y-39370D02*
X87114D01*
X86614Y-39870D02*
Y-38870D01*
X88083Y-53937D02*
X89083D01*
X88583Y-54437D02*
Y-53437D01*
X84539Y-53937D02*
X85539D01*
X85039Y-54437D02*
Y-53437D01*
X88083Y-50787D02*
X89083D01*
X88583Y-51287D02*
Y-50287D01*
X84539Y-50787D02*
X85539D01*
X85039Y-51287D02*
Y-50287D01*
X88083Y-46457D02*
X89083D01*
X88583Y-46957D02*
Y-45957D01*
X84539Y-46850D02*
X85539D01*
X85039Y-47350D02*
Y-46350D01*
X83752Y-9055D02*
X84752D01*
X84252Y-9555D02*
Y-8555D01*
X83752Y-5906D02*
X84752D01*
X84252Y-6406D02*
Y-5406D01*
X83752Y-2362D02*
X84752D01*
X84252Y-2862D02*
Y-1862D01*
X87757Y-2500D02*
X88757D01*
X88257Y-3000D02*
Y-2000D01*
X93108Y-3379D02*
X94108D01*
X93608Y-3880D02*
Y-2880D01*
X89657Y-7480D02*
X90658D01*
X90158Y-7980D02*
Y-6980D01*
X107332Y-10197D02*
X108332D01*
X107832Y-10697D02*
Y-9697D01*
X96908Y-10197D02*
X97908D01*
X97408Y-10697D02*
Y-9697D01*
X106193Y-27559D02*
X107193D01*
X106693Y-28059D02*
Y-27059D01*
X104782Y-19291D02*
X105782D01*
X105282Y-19791D02*
Y-18791D01*
X85427Y-16929D02*
X86227D01*
X85827Y-17329D02*
Y-16529D01*
X85453Y-13780D02*
X86253D01*
X85853Y-14179D02*
Y-13379D01*
X78240Y18110D02*
X79240D01*
X78740Y17610D02*
Y18610D01*
X78240Y15354D02*
X79240D01*
X78740Y14854D02*
Y15854D01*
X78240Y9843D02*
X79240D01*
X78740Y9342D02*
Y10343D01*
X78240Y6693D02*
X79240D01*
X78740Y6193D02*
Y7193D01*
X78240Y3543D02*
X79240D01*
X78740Y3043D02*
Y4043D01*
X110089Y1589D02*
X111089D01*
X110589Y1089D02*
Y2089D01*
X107768Y394D02*
X108768D01*
X108268Y-106D02*
Y894D01*
X112098Y394D02*
X113098D01*
X112598Y-106D02*
Y894D01*
X116529Y-21654D02*
X117329D01*
X116929Y-22053D02*
Y-21253D01*
X118498Y-16929D02*
X119298D01*
X118898Y-17329D02*
Y-16529D01*
X365643Y-153937D02*
X366443D01*
X366043Y-154337D02*
Y-153537D01*
X372828Y-162598D02*
X373628D01*
X373228Y-162998D02*
Y-162198D01*
X377946Y-161811D02*
X378747D01*
X378346Y-162211D02*
Y-161411D01*
X388313Y-128731D02*
X389112D01*
X388713Y-129131D02*
Y-128331D01*
X382683Y-128504D02*
X383483D01*
X383083Y-128904D02*
Y-128104D01*
X335720Y-122047D02*
X336720D01*
X336221Y-122547D02*
Y-121547D01*
X332965Y-122047D02*
X333965D01*
X333465Y-122547D02*
Y-121547D01*
X329815Y-121653D02*
X330815D01*
X330315Y-122153D02*
Y-121153D01*
X335327Y-164173D02*
X336327D01*
X335827Y-164673D02*
Y-163673D01*
X332571Y-164173D02*
X333571D01*
X333071Y-164673D02*
Y-163673D01*
X329418Y-164008D02*
X330418D01*
X329919Y-164508D02*
Y-163508D01*
X329156Y-142480D02*
X330156D01*
X329656Y-142980D02*
Y-141980D01*
X329222Y-145827D02*
X330222D01*
X329722Y-146327D02*
Y-145327D01*
X347238Y-119882D02*
X348038D01*
X347638Y-120282D02*
Y-119482D01*
X346844Y-113189D02*
X347644D01*
X347244Y-113589D02*
Y-112789D01*
X354635Y-105876D02*
X355435D01*
X355035Y-106276D02*
Y-105476D01*
X390254Y-104510D02*
X391054D01*
X390654Y-104910D02*
Y-104110D01*
X383065Y-103543D02*
X383865D01*
X383465Y-103943D02*
Y-103143D01*
X369185Y-123622D02*
X370185D01*
X369685Y-124122D02*
Y-123122D01*
X369185Y-120866D02*
X370185D01*
X369685Y-121366D02*
Y-120366D01*
X369185Y-118110D02*
X370185D01*
X369685Y-118610D02*
Y-117610D01*
X366429Y-123622D02*
X367429D01*
X366929Y-124122D02*
Y-123122D01*
X366429Y-120866D02*
X367429D01*
X366929Y-121366D02*
Y-120366D01*
X363280Y-123622D02*
X364280D01*
X363779Y-124122D02*
Y-123122D01*
X366429Y-118110D02*
X367429D01*
X366929Y-118610D02*
Y-117610D01*
X363280Y-120866D02*
X364280D01*
X363779Y-121366D02*
Y-120366D01*
X363280Y-118110D02*
X364280D01*
X363779Y-118610D02*
Y-117610D01*
X447925Y-165354D02*
X448925D01*
X448425Y-165854D02*
Y-164854D01*
X451469Y-165354D02*
X452468D01*
X451968Y-165854D02*
Y-164854D01*
X455012Y-165354D02*
X456012D01*
X455512Y-165854D02*
Y-164854D01*
X458161Y-165354D02*
X459161D01*
X458661Y-165854D02*
Y-164854D01*
X442315Y-161747D02*
X443315D01*
X442815Y-162247D02*
Y-161247D01*
X442315Y-165847D02*
X443315D01*
X442815Y-166347D02*
Y-165347D01*
X439061Y-165847D02*
X440061D01*
X439561Y-166347D02*
Y-165347D01*
X425484Y-109843D02*
X426484D01*
X425984Y-110343D02*
Y-109343D01*
X425130Y-112894D02*
X426130D01*
X425630Y-113394D02*
Y-112394D01*
X416035Y-120768D02*
X417035D01*
X416535Y-121268D02*
Y-120268D01*
X423122Y-115354D02*
X424122D01*
X423622Y-115854D02*
Y-114854D01*
X436311Y-153543D02*
X437311D01*
X436811Y-154043D02*
Y-153043D01*
X417610Y-153543D02*
X418610D01*
X418110Y-154043D02*
Y-153043D01*
X422335Y-153543D02*
X423335D01*
X422835Y-154043D02*
Y-153043D01*
X427059Y-153543D02*
X428059D01*
X427559Y-154043D02*
Y-153043D01*
X427059Y-148819D02*
X428059D01*
X427559Y-149319D02*
Y-148319D01*
X417610Y-148819D02*
X418610D01*
X418110Y-149319D02*
Y-148319D01*
X422335Y-148819D02*
X423335D01*
X422835Y-149319D02*
Y-148319D01*
X422335Y-144095D02*
X423335D01*
X422835Y-144595D02*
Y-143595D01*
X417610Y-144095D02*
X418610D01*
X418110Y-144595D02*
Y-143595D01*
X422435Y-131791D02*
X423235D01*
X422835Y-132191D02*
Y-131391D01*
X427443Y-166966D02*
X428243D01*
X427843Y-167366D02*
Y-166566D01*
X422435Y-166284D02*
X423235D01*
X422835Y-166684D02*
Y-165884D01*
X406193Y-125984D02*
X407193D01*
X406693Y-126484D02*
Y-125484D01*
X407768Y-124409D02*
X408768D01*
X408268Y-124909D02*
Y-123909D01*
X407768Y-122047D02*
X408768D01*
X408268Y-122547D02*
Y-121547D01*
X400584Y-127102D02*
X401384D01*
X400984Y-127502D02*
Y-126702D01*
X415348Y-129609D02*
X416148D01*
X415748Y-130009D02*
Y-129209D01*
X418498Y-129753D02*
X419298D01*
X418898Y-130153D02*
Y-129353D01*
X444776Y-103543D02*
X445776D01*
X445276Y-104043D02*
Y-103043D01*
X443988Y-106299D02*
X444988D01*
X444488Y-106799D02*
Y-105799D01*
X440445Y-105905D02*
X441445D01*
X440945Y-106405D02*
Y-105405D01*
X435720Y-106299D02*
X436721D01*
X436221Y-106799D02*
Y-105799D01*
X433847Y-103743D02*
X434847D01*
X434347Y-104243D02*
Y-103243D01*
X434146Y-100787D02*
X435146D01*
X434646Y-101287D02*
Y-100287D01*
X430996Y-100000D02*
X431996D01*
X431496Y-100500D02*
Y-99500D01*
X421647Y-101969D02*
X422447D01*
X422047Y-102368D02*
Y-101568D01*
X418498Y-100000D02*
X419298D01*
X418898Y-100400D02*
Y-99600D01*
X445169Y-128347D02*
X446169D01*
X445669Y-128847D02*
Y-127847D01*
X449106Y-128347D02*
X450106D01*
X449606Y-128847D02*
Y-127847D01*
X449106Y-124803D02*
X450106D01*
X449606Y-125303D02*
Y-124303D01*
X449106Y-121653D02*
X450106D01*
X449606Y-122153D02*
Y-121153D01*
X275190Y-199606D02*
X275991D01*
X275590Y-200006D02*
Y-199206D01*
X288970Y-200394D02*
X289770D01*
X289370Y-200794D02*
Y-199994D01*
X274403Y-188583D02*
X275203D01*
X274803Y-188983D02*
Y-188183D01*
X291431Y-197012D02*
X292231D01*
X291831Y-197412D02*
Y-196612D01*
X295269Y-191339D02*
X296069D01*
X295669Y-191739D02*
Y-190939D01*
X292415Y-187106D02*
X293215D01*
X292815Y-187506D02*
Y-186706D01*
X275190Y-184252D02*
X275991D01*
X275590Y-184652D02*
Y-183852D01*
X281490Y-188583D02*
X282290D01*
X281890Y-188983D02*
Y-188183D01*
X281490Y-200771D02*
X282290D01*
X281890Y-201171D02*
Y-200371D01*
X288183Y-195276D02*
X288983D01*
X288583Y-195676D02*
Y-194876D01*
X275103Y-195276D02*
X275903D01*
X275503Y-195676D02*
Y-194876D01*
X595663Y-239895D02*
X596463D01*
X596063Y-240295D02*
Y-239495D01*
X595663Y-241995D02*
X596463D01*
X596063Y-242395D02*
Y-241595D01*
X321253Y-232677D02*
X322054D01*
X321654Y-233077D02*
Y-232277D01*
X336214Y-286221D02*
X337014D01*
X336614Y-286620D02*
Y-285821D01*
X315545Y-287795D02*
X316345D01*
X315945Y-288195D02*
Y-287395D01*
X314933Y-299430D02*
X315733D01*
X315333Y-299830D02*
Y-299030D01*
X336411Y-299399D02*
X337211D01*
X336811Y-299799D02*
Y-298999D01*
X312986Y-283465D02*
X313786D01*
X313386Y-283865D02*
Y-283065D01*
X307868Y-300000D02*
X308668D01*
X308268Y-300400D02*
Y-299600D01*
X323784Y-302194D02*
X324584D01*
X324184Y-302594D02*
Y-301794D01*
X356293Y-288583D02*
X357093D01*
X356693Y-288983D02*
Y-288183D01*
X355341Y-296063D02*
X356141D01*
X355741Y-296463D02*
Y-295663D01*
X314561Y-293701D02*
X315361D01*
X314961Y-294101D02*
Y-293301D01*
X320072Y-299569D02*
X320872D01*
X320472Y-299969D02*
Y-299169D01*
X325376Y-293701D02*
X326176D01*
X325776Y-294101D02*
Y-293301D01*
X320072Y-287865D02*
X320872D01*
X320472Y-288265D02*
Y-287465D01*
X344761Y-292913D02*
X345561D01*
X345161Y-293313D02*
Y-292513D01*
X333065Y-292913D02*
X333865D01*
X333465Y-293313D02*
Y-292513D01*
X338970Y-286162D02*
X339770D01*
X339370Y-286562D02*
Y-285762D01*
X338970Y-298819D02*
X339770D01*
X339370Y-299219D02*
Y-298419D01*
X328734Y-228740D02*
X329534D01*
X329134Y-229140D02*
Y-228340D01*
X340875Y-242913D02*
X341674D01*
X341274Y-243313D02*
Y-242513D01*
X340386Y-235827D02*
X341185D01*
X340786Y-236227D02*
Y-235427D01*
X311922Y-236221D02*
X312722D01*
X312322Y-236620D02*
Y-235821D01*
X309382Y-243307D02*
X310182D01*
X309782Y-243707D02*
Y-242907D01*
X334442Y-247244D02*
X335243D01*
X334842Y-247644D02*
Y-246844D01*
X319285Y-245276D02*
X320085D01*
X319685Y-245676D02*
Y-244876D01*
X333314Y-239764D02*
X334114D01*
X333714Y-240164D02*
Y-239364D01*
X325190Y-246324D02*
X325991D01*
X325590Y-246724D02*
Y-245924D01*
X325190Y-232344D02*
X325991D01*
X325590Y-232744D02*
Y-231944D01*
X316609Y-239764D02*
X317409D01*
X317009Y-240164D02*
Y-239364D01*
X390496Y-249065D02*
X391296D01*
X390896Y-249465D02*
Y-248665D01*
X386215Y-249113D02*
X387015D01*
X386615Y-249513D02*
Y-248713D01*
X399600Y-219291D02*
X400400D01*
X400000Y-219691D02*
Y-218891D01*
X398073Y-235531D02*
X398872D01*
X398472Y-235931D02*
Y-235132D01*
X378537Y-249803D02*
X379337D01*
X378937Y-250203D02*
Y-249403D01*
X367254Y-236614D02*
X368054D01*
X367654Y-237014D02*
Y-236214D01*
X372693Y-232972D02*
X373493D01*
X373093Y-233372D02*
Y-232572D01*
X374797Y-221260D02*
X375597D01*
X375197Y-221660D02*
Y-220860D01*
X382376Y-221555D02*
X383176D01*
X382776Y-221955D02*
Y-221155D01*
X367832Y-217717D02*
X368632D01*
X368232Y-218116D02*
Y-217317D01*
X389757Y-217717D02*
X390558D01*
X390158Y-218116D02*
Y-217317D01*
X415223Y-358391D02*
X416023D01*
X415623Y-358791D02*
Y-357991D01*
X414372Y-353273D02*
X415172D01*
X414772Y-353673D02*
Y-352873D01*
X448750Y-355832D02*
X449550D01*
X449150Y-356232D02*
Y-355432D01*
X460278Y-359179D02*
X461078D01*
X460678Y-359579D02*
Y-358779D01*
X460500Y-354061D02*
X461300D01*
X460900Y-354461D02*
Y-353661D01*
X492834Y-356620D02*
X493634D01*
X493234Y-357020D02*
Y-356220D01*
X533531Y-356296D02*
X534331D01*
X533931Y-356696D02*
Y-355896D01*
X499125Y-358855D02*
X499926D01*
X499525Y-359255D02*
Y-358455D01*
X498902Y-353737D02*
X499702D01*
X499302Y-354137D02*
Y-353337D01*
X578672Y-356690D02*
X579472D01*
X579072Y-357090D02*
Y-356290D01*
X560930Y-356099D02*
X561730D01*
X561330Y-356499D02*
Y-355699D01*
X543298Y-358659D02*
X544098D01*
X543698Y-359058D02*
Y-358259D01*
X543318Y-353540D02*
X544118D01*
X543718Y-353940D02*
Y-353140D01*
X626587Y-228346D02*
X627387D01*
X626987Y-228747D02*
Y-227946D01*
X605112Y-261024D02*
X605912D01*
X605512Y-261424D02*
Y-260624D01*
X605112Y-256693D02*
X605912D01*
X605512Y-257093D02*
Y-256293D01*
X622435Y-244094D02*
X623235D01*
X622835Y-244495D02*
Y-243694D01*
X622435Y-235433D02*
X623235D01*
X622835Y-235833D02*
Y-235033D01*
X618104Y-252362D02*
X618904D01*
X618504Y-252762D02*
Y-251962D01*
X621701Y-250000D02*
X622501D01*
X622101Y-250400D02*
Y-249600D01*
X622403Y-241006D02*
X623203D01*
X622803Y-241406D02*
Y-240606D01*
X604917Y-252756D02*
X605717D01*
X605317Y-253156D02*
Y-252356D01*
X609836Y-300000D02*
X610636D01*
X610236Y-300400D02*
Y-299600D01*
X618748Y-302756D02*
X619548D01*
X619148Y-303156D02*
Y-302356D01*
X621821Y-313481D02*
X622621D01*
X622221Y-313881D02*
Y-313081D01*
X622353Y-353307D02*
X623153D01*
X622753Y-353707D02*
Y-352907D01*
X622277Y-333307D02*
X623077D01*
X622677Y-333707D02*
Y-332907D01*
X622828Y-343307D02*
X623628D01*
X623228Y-343707D02*
Y-342907D01*
X598183Y-353307D02*
X598983D01*
X598583Y-353707D02*
Y-352907D01*
X598419Y-343307D02*
X599219D01*
X598819Y-343707D02*
Y-342907D01*
X598559Y-333307D02*
X599359D01*
X598959Y-333707D02*
Y-332907D01*
X598498Y-313307D02*
X599298D01*
X598898Y-313707D02*
Y-312907D01*
X393301Y-168898D02*
X394101D01*
X393701Y-169298D02*
Y-168498D01*
X378194Y-166966D02*
X378994D01*
X378594Y-167366D02*
Y-166566D01*
X347632Y-165748D02*
X348431D01*
X348031Y-166148D02*
Y-165348D01*
X342408Y-166966D02*
X343208D01*
X342808Y-167366D02*
Y-166566D01*
X337395Y-181102D02*
X338195D01*
X337795Y-181502D02*
Y-180702D01*
X333852Y-180315D02*
X334652D01*
X334252Y-180715D02*
Y-179915D01*
X309836Y-165748D02*
X310636D01*
X310236Y-166148D02*
Y-165348D01*
X308655Y-195669D02*
X309455D01*
X309055Y-196069D02*
Y-195269D01*
X314275Y-198819D02*
X315075D01*
X314675Y-199219D02*
Y-198419D01*
X318891Y-196850D02*
X319691D01*
X319291Y-197250D02*
Y-196450D01*
X322435Y-196063D02*
X323235D01*
X322835Y-196463D02*
Y-195663D01*
X373330Y-202888D02*
X374130D01*
X373730Y-203288D02*
Y-202488D01*
X375298Y-197700D02*
X376098D01*
X375698Y-198100D02*
Y-197300D01*
X383172Y-206205D02*
X383972D01*
X383572Y-206605D02*
Y-205804D01*
X385141Y-202460D02*
X385941D01*
X385541Y-202860D02*
Y-202060D01*
X155027Y-33907D02*
X155827D01*
X155427Y-34307D02*
Y-33507D01*
X154928Y-26033D02*
X155728D01*
X155328Y-26433D02*
Y-25633D01*
X122139Y-26033D02*
X122939D01*
X122539Y-26433D02*
Y-25633D01*
X141726Y-348031D02*
X142526D01*
X142126Y-348431D02*
Y-347632D01*
X141188Y-352161D02*
X141988D01*
X141587Y-352561D02*
Y-351761D01*
X377258Y-346144D02*
X378058D01*
X377658Y-346544D02*
Y-345744D01*
X256490Y-374655D02*
X257290D01*
X256890Y-375055D02*
Y-374255D01*
X380407Y-346144D02*
X381207D01*
X380807Y-346544D02*
Y-345744D01*
X253255Y-374421D02*
X254055D01*
X253655Y-374821D02*
Y-374021D01*
X269102Y-374291D02*
X269902D01*
X269502Y-374691D02*
Y-373891D01*
X273025Y-374655D02*
X273825D01*
X273425Y-375055D02*
Y-374255D01*
X373714Y-328034D02*
X374515D01*
X374114Y-328434D02*
Y-327634D01*
X370959Y-328034D02*
X371759D01*
X371359Y-328434D02*
Y-327634D01*
X473595Y-331073D02*
X485795D01*
X479695Y-337173D02*
Y-324973D01*
X575957Y-92884D02*
X588158D01*
X582058Y-98984D02*
Y-86784D01*
X473595Y-92884D02*
X485795D01*
X479695Y-98984D02*
Y-86784D01*
X575957Y-331073D02*
X588158D01*
X582058Y-337173D02*
Y-324973D01*
X21647Y-335433D02*
X22447D01*
X22047Y-335833D02*
Y-335033D01*
X1697Y-349213D02*
X2497D01*
X2097Y-349613D02*
Y-348813D01*
X26667Y-282677D02*
X27467D01*
X27067Y-283077D02*
Y-282277D01*
X5184Y-238905D02*
X5984D01*
X5584Y-239305D02*
Y-238505D01*
X34720Y-228937D02*
X35520D01*
X35120Y-229337D02*
Y-228537D01*
X10230Y-197638D02*
X11030D01*
X10630Y-198038D02*
Y-197238D01*
X19577Y-200787D02*
X20377D01*
X19976Y-201187D02*
Y-200387D01*
X19577Y-220472D02*
X20377D01*
X19976Y-220872D02*
Y-220072D01*
X21941Y-167323D02*
X22941D01*
X22441Y-167823D02*
Y-166823D01*
X19185Y-167323D02*
X20185D01*
X19685Y-167823D02*
Y-166823D01*
X16429Y-167323D02*
X17429D01*
X16929Y-167823D02*
Y-166823D01*
X22728Y-147244D02*
X23728D01*
X23228Y-147744D02*
Y-146744D01*
X19579Y-147244D02*
X20579D01*
X20079Y-147744D02*
Y-146744D01*
X16823Y-147244D02*
X17823D01*
X17323Y-147744D02*
Y-146744D01*
X26765Y-179134D02*
X27565D01*
X27165Y-179534D02*
Y-178734D01*
X-8274Y-188976D02*
X-7474D01*
X-7874Y-189376D02*
Y-188576D01*
X363773Y-332283D02*
X364573D01*
X364173Y-332683D02*
Y-331884D01*
X369679Y-332283D02*
X370479D01*
X370079Y-332683D02*
Y-331884D01*
X377258Y-327985D02*
X378058D01*
X377658Y-328385D02*
Y-327585D01*
X369303Y-326432D02*
X370103D01*
X369703Y-326832D02*
Y-326032D01*
X344482Y-328346D02*
X345282D01*
X344882Y-328747D02*
Y-327946D01*
X348025Y-328740D02*
X348825D01*
X348425Y-329140D02*
Y-328340D01*
X381589Y-348458D02*
X382388D01*
X381989Y-348858D02*
Y-348058D01*
X376470Y-348458D02*
X377270D01*
X376870Y-348858D02*
Y-348058D01*
X374502Y-348458D02*
X375302D01*
X374902Y-348858D02*
Y-348058D01*
X370072Y-348425D02*
X370872D01*
X370472Y-348825D02*
Y-348025D01*
X367894Y-348913D02*
X368694D01*
X368294Y-349313D02*
Y-348513D01*
X363478Y-348458D02*
X364278D01*
X363878Y-348858D02*
Y-348058D01*
X361510Y-348458D02*
X362310D01*
X361910Y-348858D02*
Y-348058D01*
X356392Y-348458D02*
X357192D01*
X356792Y-348858D02*
Y-348058D01*
X349305Y-348064D02*
X350105D01*
X349705Y-348464D02*
Y-347664D01*
X354423Y-348851D02*
X355223D01*
X354823Y-349252D02*
Y-348451D01*
X156293Y-18110D02*
X157093D01*
X156693Y-18510D02*
Y-17710D01*
X203289Y-248906D02*
X204089D01*
X203689Y-249306D02*
Y-248506D01*
X203537Y-242913D02*
X204337D01*
X203937Y-243313D02*
Y-242513D01*
X451273Y-283940D02*
X452073D01*
X451674Y-284340D02*
Y-283540D01*
X381589Y-331971D02*
X382388D01*
X381989Y-332371D02*
Y-331571D01*
X369777Y-315042D02*
X370578D01*
X370178Y-315442D02*
Y-314642D01*
X342218Y-315081D02*
X343018D01*
X342618Y-315481D02*
Y-314681D01*
X451273Y-234727D02*
X452073D01*
X451674Y-235127D02*
Y-234327D01*
X258302Y-264859D02*
X259102D01*
X258702Y-265259D02*
Y-264459D01*
X445368Y-254381D02*
X446168D01*
X445768Y-254781D02*
Y-253981D01*
X359474Y-183841D02*
X360274D01*
X359874Y-184241D02*
Y-183441D01*
X262922Y-246466D02*
X263722D01*
X263322Y-246866D02*
Y-246066D01*
X340447Y-179215D02*
X341247D01*
X340847Y-179615D02*
Y-178815D01*
X451273Y-244570D02*
X452073D01*
X451674Y-244970D02*
Y-244170D01*
X258360Y-256529D02*
X259160D01*
X258760Y-256929D02*
Y-256129D01*
X445368Y-264255D02*
X446168D01*
X445768Y-264655D02*
Y-263855D01*
X349927Y-183546D02*
X350727D01*
X350327Y-183946D02*
Y-183146D01*
X263222Y-236666D02*
X264022D01*
X263622Y-237066D02*
Y-236266D01*
X352061Y-315042D02*
X352861D01*
X352461Y-315442D02*
Y-314642D01*
X330305Y-179215D02*
X331105D01*
X330705Y-179615D02*
Y-178815D01*
X262722Y-285766D02*
X263522D01*
X263122Y-286166D02*
Y-285366D01*
X363872Y-315042D02*
X364672D01*
X364272Y-315442D02*
Y-314642D01*
X342612Y-332365D02*
X343412D01*
X343012Y-332765D02*
Y-331965D01*
X451273Y-254381D02*
X452073D01*
X451674Y-254781D02*
Y-253981D01*
X349927Y-179215D02*
X350727D01*
X350327Y-179615D02*
Y-178815D01*
X258222Y-246466D02*
X259022D01*
X258622Y-246866D02*
Y-246066D01*
X322533Y-332365D02*
X323333D01*
X322933Y-332765D02*
Y-331965D01*
X445368Y-275261D02*
X446168D01*
X445768Y-275661D02*
Y-274861D01*
X339856Y-183841D02*
X340656D01*
X340256Y-184241D02*
Y-183441D01*
X263180Y-226943D02*
X263980D01*
X263580Y-227343D02*
Y-226543D01*
X445368Y-224885D02*
X446168D01*
X445768Y-225285D02*
Y-224484D01*
X320073Y-179117D02*
X320873D01*
X320473Y-179517D02*
Y-178717D01*
X262922Y-276066D02*
X263722D01*
X263322Y-276466D02*
Y-275666D01*
X351706Y-332482D02*
X352506D01*
X352106Y-332882D02*
Y-332082D01*
X451273Y-264255D02*
X452073D01*
X451674Y-264655D02*
Y-263855D01*
X258622Y-236566D02*
X259422D01*
X259022Y-236966D02*
Y-236166D01*
X322140Y-315042D02*
X322940D01*
X322540Y-315442D02*
Y-314642D01*
X445368Y-283940D02*
X446168D01*
X445768Y-284340D02*
Y-283540D01*
X330691Y-184050D02*
X331491D01*
X331091Y-184450D02*
Y-183650D01*
X258222Y-285766D02*
X259022D01*
X258622Y-286166D02*
Y-285366D01*
X376077Y-315042D02*
X376877D01*
X376477Y-315442D02*
Y-314642D01*
X357573Y-315042D02*
X358373D01*
X357973Y-315442D02*
Y-314642D01*
X445368Y-234727D02*
X446168D01*
X445768Y-235127D02*
Y-234327D01*
X379096Y-183803D02*
X379896D01*
X379496Y-184203D02*
Y-183403D01*
X379096Y-179215D02*
X379896D01*
X379496Y-179614D02*
Y-178814D01*
X262522Y-265040D02*
X263322D01*
X262922Y-265440D02*
Y-264640D01*
X332376Y-332365D02*
X333176D01*
X332776Y-332765D02*
Y-331965D01*
X451273Y-275261D02*
X452073D01*
X451674Y-275661D02*
Y-274861D01*
X369581Y-179215D02*
X370381D01*
X369981Y-179615D02*
Y-178815D01*
X258522Y-226766D02*
X259322D01*
X258922Y-227166D02*
Y-226366D01*
X451273Y-224885D02*
X452073D01*
X451674Y-225285D02*
Y-224484D01*
X359738Y-179215D02*
X360538D01*
X360138Y-179615D02*
Y-178815D01*
X258222Y-276066D02*
X259022D01*
X258622Y-276466D02*
Y-275666D01*
X381195Y-315042D02*
X381995D01*
X381595Y-315442D02*
Y-314642D01*
X445368Y-244570D02*
X446168D01*
X445768Y-244970D02*
Y-244170D01*
X369285Y-183841D02*
X370085D01*
X369685Y-184241D02*
Y-183441D01*
X263281Y-256529D02*
X264081D01*
X263681Y-256929D02*
Y-256129D01*
X331982Y-315042D02*
X332782D01*
X332382Y-315442D02*
Y-314642D01*
X19577Y-252953D02*
X20377D01*
X19976Y-253353D02*
Y-252553D01*
X19577Y-272638D02*
X20377D01*
X19976Y-273038D02*
Y-272238D01*
X19577Y-326772D02*
X20377D01*
X19976Y-327172D02*
Y-326372D01*
X19577Y-307087D02*
X20377D01*
X19976Y-307487D02*
Y-306687D01*
X100329Y-123872D02*
X101129D01*
X100729Y-124272D02*
Y-123471D01*
X162671Y-390730D02*
X163471D01*
X163071Y-391130D02*
Y-390330D01*
X258885Y-390247D02*
X259685D01*
X259285Y-390647D02*
Y-389847D01*
X266804Y-390009D02*
X267604D01*
X267204Y-390409D02*
Y-389610D01*
X215762Y-390947D02*
X216562D01*
X216162Y-391347D02*
Y-390547D01*
X234744Y-390416D02*
X235544D01*
X235144Y-390816D02*
Y-390016D01*
X251056Y-390009D02*
X251856D01*
X251456Y-390409D02*
Y-389610D01*
X225663Y-390722D02*
X226463D01*
X226063Y-391122D02*
Y-390322D01*
X280801Y-390009D02*
X281601D01*
X281201Y-390409D02*
Y-389610D01*
X174541Y-390600D02*
X175341D01*
X174941Y-391000D02*
Y-390200D01*
X202041Y-390600D02*
X202841D01*
X202441Y-391000D02*
Y-390200D01*
X-24022Y-187992D02*
X-23222D01*
X-23622Y-188392D02*
Y-187592D01*
X26372Y-348819D02*
X27172D01*
X26772Y-349219D02*
Y-348419D01*
X-1581Y-352831D02*
X-781D01*
X-1181Y-353231D02*
Y-352431D01*
X3931Y-344488D02*
X4731D01*
X4331Y-344888D02*
Y-344088D01*
X12198Y-349213D02*
X12998D01*
X12598Y-349613D02*
Y-348813D01*
X34639Y-289961D02*
X35439D01*
X35039Y-290361D02*
Y-289561D01*
X34639Y-285827D02*
X35439D01*
X35039Y-286227D02*
Y-285427D01*
X26667Y-298727D02*
X27467D01*
X27067Y-299127D02*
Y-298327D01*
X10230Y-292126D02*
X11030D01*
X10630Y-292526D02*
Y-291726D01*
X13773Y-294320D02*
X14573D01*
X14173Y-294720D02*
Y-293919D01*
X-112Y-234968D02*
X688D01*
X288Y-235368D02*
Y-234568D01*
X9607Y-234968D02*
X10407D01*
X10007Y-235368D02*
Y-234568D01*
X19285Y-239370D02*
X20085D01*
X19685Y-239770D02*
Y-238970D01*
X14265Y-237402D02*
X15065D01*
X14665Y-237802D02*
Y-237002D01*
X35820Y-235039D02*
X36621D01*
X36220Y-235439D02*
Y-234639D01*
X36214Y-232677D02*
X37014D01*
X36614Y-233077D02*
Y-232277D01*
X34639Y-237402D02*
X35439D01*
X35039Y-237802D02*
Y-237002D01*
X30309Y-190411D02*
X31109D01*
X30709Y-190811D02*
Y-190011D01*
X32671Y-185755D02*
X33471D01*
X33071Y-186155D02*
Y-185355D01*
X35427Y-185755D02*
X36227D01*
X35827Y-186155D02*
Y-185355D01*
X13379Y-190551D02*
X14179D01*
X13780Y-190951D02*
Y-190151D01*
X9443Y-185755D02*
X10243D01*
X9843Y-186155D02*
Y-185355D01*
X19282Y-192520D02*
X20082D01*
X19682Y-192920D02*
Y-192120D01*
X-11030Y-178347D02*
X-10230D01*
X-10630Y-178746D02*
Y-177946D01*
X197992Y-366842D02*
X198792D01*
X198392Y-367242D02*
Y-366442D01*
X196301Y-370523D02*
X197101D01*
X196701Y-370923D02*
Y-370123D01*
X393793Y-197670D02*
X394593D01*
X394193Y-198070D02*
Y-197270D01*
X379963Y-196740D02*
X380764D01*
X380363Y-197140D02*
Y-196340D01*
X157080Y-361811D02*
X157880D01*
X157480Y-362211D02*
Y-361411D01*
X153143Y-358661D02*
X153943D01*
X153543Y-359061D02*
Y-358261D01*
X153143Y-361811D02*
X153943D01*
X153543Y-362211D02*
Y-361411D01*
X155112Y-361811D02*
X155912D01*
X155512Y-362211D02*
Y-361411D01*
X155112Y-358661D02*
X155912D01*
X155512Y-359061D02*
Y-358261D01*
X157080Y-358661D02*
X157880D01*
X157480Y-359061D02*
Y-358261D01*
X156687Y-41732D02*
X157487D01*
X157087Y-42132D02*
Y-41332D01*
X229765Y-235119D02*
X230565D01*
X230165Y-235519D02*
Y-234719D01*
X245762Y-293733D02*
X246562D01*
X246162Y-294133D02*
Y-293333D01*
X230006Y-251861D02*
X230806D01*
X230406Y-252261D02*
Y-251461D01*
X229851Y-232266D02*
X230651D01*
X230251Y-232666D02*
Y-231866D01*
X203931Y-232677D02*
X204731D01*
X204331Y-233077D02*
Y-232277D01*
X203537Y-235827D02*
X204337D01*
X203937Y-236227D02*
Y-235427D01*
X203537Y-238189D02*
X204337D01*
X203937Y-238589D02*
Y-237789D01*
X203405Y-240564D02*
X204205D01*
X203805Y-240964D02*
Y-240164D01*
X203405Y-252182D02*
X204205D01*
X203805Y-252582D02*
Y-251782D01*
X203537Y-254724D02*
X204337D01*
X203937Y-255124D02*
Y-254324D01*
X154324Y-389616D02*
X155124D01*
X154724Y-390016D02*
Y-389216D01*
X156293Y-389616D02*
X157093D01*
X156693Y-390016D02*
Y-389216D01*
X158261Y-389616D02*
X159061D01*
X158661Y-390016D02*
Y-389216D01*
X154324Y-386466D02*
X155124D01*
X154724Y-386866D02*
Y-386066D01*
X156293Y-386466D02*
X157093D01*
X156693Y-386866D02*
Y-386066D01*
X158261Y-386466D02*
X159061D01*
X158661Y-386866D02*
Y-386066D01*
X280014Y-293782D02*
X280814D01*
X280414Y-294182D02*
Y-293382D01*
X245565Y-264497D02*
X246365D01*
X245965Y-264897D02*
Y-264097D01*
X245565Y-254655D02*
X246365D01*
X245965Y-255055D02*
Y-254255D01*
X432435Y-291755D02*
X433235D01*
X432835Y-292155D02*
Y-291355D01*
X471647Y-221260D02*
X472447D01*
X472047Y-221660D02*
Y-220860D01*
X429620Y-218979D02*
X430420D01*
X430020Y-219379D02*
Y-218579D01*
X471647Y-223228D02*
X472447D01*
X472047Y-223628D02*
Y-222828D01*
X429620Y-220948D02*
X430420D01*
X430020Y-221347D02*
Y-220548D01*
X429620Y-222916D02*
X430420D01*
X430020Y-223316D02*
Y-222516D01*
X471647Y-219291D02*
X472447D01*
X472047Y-219691D02*
Y-218891D01*
X429620Y-217010D02*
X430420D01*
X430020Y-217410D02*
Y-216611D01*
X121057Y-57529D02*
X121857D01*
X121457Y-57929D02*
Y-57129D01*
X279982Y-274277D02*
X280782D01*
X280382Y-274677D02*
Y-273877D01*
X337374Y-196489D02*
X338174D01*
X337774Y-196889D02*
Y-196089D01*
X274319Y-244928D02*
X275119D01*
X274719Y-245328D02*
Y-244528D01*
X276355Y-246539D02*
X277155D01*
X276755Y-246939D02*
Y-246139D01*
X280014Y-283478D02*
X280814D01*
X280414Y-283878D02*
Y-283078D01*
X280014Y-287478D02*
X280814D01*
X280414Y-287878D02*
Y-287078D01*
X330820Y-196266D02*
X331620D01*
X331220Y-196667D02*
Y-195867D01*
X341374Y-196326D02*
X342174D01*
X341774Y-196726D02*
Y-195926D01*
X326305Y-179059D02*
X327105D01*
X326705Y-179459D02*
Y-178659D01*
X324305Y-184678D02*
X325105D01*
X324705Y-185078D02*
Y-184278D01*
X463053Y-247883D02*
X463853D01*
X463453Y-248283D02*
Y-247483D01*
X464072Y-245540D02*
X464872D01*
X464472Y-245940D02*
Y-245140D01*
X327258Y-184678D02*
X328058D01*
X327658Y-185078D02*
Y-184278D01*
X36214Y18701D02*
X37014D01*
X36614Y18301D02*
Y19101D01*
X243628Y-262466D02*
X244428D01*
X244028Y-262866D02*
Y-262066D01*
X243628Y-258497D02*
X244428D01*
X244028Y-258897D02*
Y-258097D01*
X243596Y-252592D02*
X244396D01*
X243996Y-252992D02*
Y-252192D01*
X245565Y-250655D02*
X246365D01*
X245965Y-251055D02*
Y-250255D01*
X243596Y-248655D02*
X244396D01*
X243996Y-249055D02*
Y-248255D01*
X245565Y-260497D02*
X246365D01*
X245965Y-260897D02*
Y-260097D01*
X-24022Y-342520D02*
X-23222D01*
X-23622Y-342920D02*
Y-342120D01*
X100329Y-119871D02*
X101129D01*
X100729Y-120272D02*
Y-119472D01*
X-24022Y-229331D02*
X-23222D01*
X-23622Y-229731D02*
Y-228931D01*
X-24022Y-233268D02*
X-23222D01*
X-23622Y-233668D02*
Y-232868D01*
X-24022Y-237205D02*
X-23222D01*
X-23622Y-237605D02*
Y-236805D01*
X-24022Y-241142D02*
X-23222D01*
X-23622Y-241542D02*
Y-240742D01*
X-24022Y-282480D02*
X-23222D01*
X-23622Y-282880D02*
Y-282080D01*
X-24022Y-286417D02*
X-23222D01*
X-23622Y-286817D02*
Y-286017D01*
X-24022Y-290354D02*
X-23222D01*
X-23622Y-290754D02*
Y-289954D01*
X-24022Y-294291D02*
X-23222D01*
X-23622Y-294691D02*
Y-293891D01*
X-24022Y-335630D02*
X-23222D01*
X-23622Y-336030D02*
Y-335230D01*
X-24022Y-339567D02*
X-23222D01*
X-23622Y-339967D02*
Y-339167D01*
X-24022Y-66929D02*
X-23222D01*
X-23622Y-67329D02*
Y-66529D01*
X-24022Y-62992D02*
X-23222D01*
X-23622Y-63392D02*
Y-62592D01*
X-24022Y-60039D02*
X-23222D01*
X-23622Y-60439D02*
Y-59639D01*
X-24022Y-102362D02*
X-23222D01*
X-23622Y-102762D02*
Y-101962D01*
X-24022Y-106299D02*
X-23222D01*
X-23622Y-106699D02*
Y-105899D01*
X-24022Y-110236D02*
X-23222D01*
X-23622Y-110636D02*
Y-109836D01*
X-24022Y-184055D02*
X-23222D01*
X-23622Y-184455D02*
Y-183655D01*
X-24022Y-177165D02*
X-23222D01*
X-23622Y-177565D02*
Y-176765D01*
X471647Y-217323D02*
X472447D01*
X472047Y-217723D02*
Y-216923D01*
X189954Y-377411D02*
X190754D01*
X190354Y-377811D02*
Y-377011D01*
X178143Y-377411D02*
X178943D01*
X178543Y-377811D02*
Y-377011D01*
X362198Y-197244D02*
X362998D01*
X362598Y-197644D02*
Y-196844D01*
X36362Y11811D02*
X37162D01*
X36762Y11411D02*
Y12211D01*
X36214Y4921D02*
X37014D01*
X36614Y4521D02*
Y5321D01*
X36214Y-1969D02*
X37014D01*
X36614Y-2369D02*
Y-1568D01*
X389167Y-196440D02*
X389967D01*
X389567Y-196840D02*
Y-196040D01*
X432179Y-283251D02*
X432979D01*
X432579Y-283651D02*
Y-282851D01*
X432179Y-286400D02*
X432979D01*
X432579Y-286800D02*
Y-286000D01*
X432320Y-289358D02*
X433120D01*
X432720Y-289758D02*
Y-288958D01*
M02*
